G04 ================== begin FILE IDENTIFICATION RECORD ==================*
G04 Layout Name:  D:/<user>/Wistron_project/16342-2/gbr/16342-2.brd*
G04 Film Name:    BMASK*
G04 File Format:  Gerber RS274X*
G04 File Origin:  Cadence Allegro 16.5-S056*
G04 Origin Date:  Mon Aug 07 11:24:06 2017*
G04 *
G04 Layer:  VIA CLASS/SOLDERMASK_BOTTOM*
G04 Layer:  PIN/SOLDERMASK_BOTTOM*
G04 Layer:  PACKAGE GEOMETRY/SOLDERMASK_BOTTOM*
G04 Layer:  DRAWING FORMAT/LAYER_PCB_STORY*
G04 Layer:  DRAWING FORMAT/LAYER_SOLDER_B*
G04 Layer:  BOARD GEOMETRY/SOLDERMASK_BOTTOM*
G04 *
G04 Offset:    (0.00 0.00)*
G04 Mirror:    No*
G04 Mode:      Positive*
G04 Rotation:  0*
G04 FullContactRelief:  No*
G04 UndefLineWidth:     6.00*
G04 ================== end FILE IDENTIFICATION RECORD ====================*
%FSLAX35Y35*MOIN*%
%IR0*IPPOS*OFA0.00000B0.00000*MIA0B0*SFA1.00000B1.00000*%
%AMMACRO42*
4,1,40,.011,.007,
.011,-.007,
.010939,-.007695,
.010759,-.008368,
.010464,-.009,
.010064,-.009571,
.009571,-.010064,
.009,-.010464,
.008368,-.010759,
.007695,-.010939,
.007,-.011,
-.007,-.011,
-.007695,-.010939,
-.008368,-.010759,
-.009,-.010464,
-.009571,-.010064,
-.010064,-.009571,
-.010464,-.009,
-.010759,-.008368,
-.010939,-.007695,
-.011,-.007,
-.011,.007,
-.010939,.007695,
-.010759,.008368,
-.010464,.009,
-.010064,.009571,
-.009571,.010064,
-.009,.010464,
-.008368,.010759,
-.007695,.010939,
-.007,.011,
.007,.011,
.007695,.010939,
.008368,.010759,
.009,.010464,
.009571,.010064,
.010064,.009571,
.010464,.009,
.010759,.008368,
.010939,.007695,
.011,.007,
0.0*
%
%ADD42MACRO42*%
%AMMACRO26*
4,1,40,-.017,-.013,
-.017,.013,
-.016939,.013695,
-.016759,.014368,
-.016464,.015,
-.016064,.015571,
-.015571,.016064,
-.015,.016464,
-.014368,.016759,
-.013695,.016939,
-.013,.017,
.013,.017,
.013695,.016939,
.014368,.016759,
.015,.016464,
.015571,.016064,
.016064,.015571,
.016464,.015,
.016759,.014368,
.016939,.013695,
.017,.013,
.017,-.013,
.016939,-.013695,
.016759,-.014368,
.016464,-.015,
.016064,-.015571,
.015571,-.016064,
.015,-.016464,
.014368,-.016759,
.013695,-.016939,
.013,-.017,
-.013,-.017,
-.013695,-.016939,
-.014368,-.016759,
-.015,-.016464,
-.015571,-.016064,
-.016064,-.015571,
-.016464,-.015,
-.016759,-.014368,
-.016939,-.013695,
-.017,-.013,
0.0*
%
%ADD26MACRO26*%
%AMMACRO24*
4,1,40,.013,-.017,
-.013,-.017,
-.013695,-.016939,
-.014368,-.016759,
-.015,-.016464,
-.015571,-.016064,
-.016064,-.015571,
-.016464,-.015,
-.016759,-.014368,
-.016939,-.013695,
-.017,-.013,
-.017,.013,
-.016939,.013695,
-.016759,.014368,
-.016464,.015,
-.016064,.015571,
-.015571,.016064,
-.015,.016464,
-.014368,.016759,
-.013695,.016939,
-.013,.017,
.013,.017,
.013695,.016939,
.014368,.016759,
.015,.016464,
.015571,.016064,
.016064,.015571,
.016464,.015,
.016759,.014368,
.016939,.013695,
.017,.013,
.017,-.013,
.016939,-.013695,
.016759,-.014368,
.016464,-.015,
.016064,-.015571,
.015571,-.016064,
.015,-.016464,
.014368,-.016759,
.013695,-.016939,
.013,-.017,
0.0*
%
%ADD24MACRO24*%
%ADD52O,.06X.111*%
%ADD11C,.02*%
%ADD59C,.03*%
%ADD70C,.05*%
%ADD50C,.014*%
%ADD45C,.032*%
%ADD51C,.042*%
%ADD21C,.024*%
%ADD56C,.034*%
%ADD68C,.044*%
%ADD12C,.08*%
%ADD69C,.063*%
%ADD43C,.028*%
%ADD10C,.056*%
%ADD54C,.048*%
%ADD64C,.094*%
%ADD13C,.086*%
%ADD63C,.097*%
%AMMACRO57*
4,1,40,.008,.014,
-.008,.014,
-.008695,.013939,
-.009368,.013759,
-.01,.013464,
-.010571,.013064,
-.011064,.012571,
-.011464,.012,
-.011759,.011368,
-.011939,.010695,
-.012,.01,
-.012,-.01,
-.011939,-.010695,
-.011759,-.011368,
-.011464,-.012,
-.011064,-.012571,
-.010571,-.013064,
-.01,-.013464,
-.009368,-.013759,
-.008695,-.013939,
-.008,-.014,
.008,-.014,
.008695,-.013939,
.009368,-.013759,
.01,-.013464,
.010571,-.013064,
.011064,-.012571,
.011464,-.012,
.011759,-.011368,
.011939,-.010695,
.012,-.01,
.012,.01,
.011939,.010695,
.011759,.011368,
.011464,.012,
.011064,.012571,
.010571,.013064,
.01,.013464,
.009368,.013759,
.008695,.013939,
.008,.014,
0.0*
%
%ADD57MACRO57*%
%AMMACRO65*
4,1,40,.007,-.0225,
.008389,-.022378,
.009736,-.022018,
.011,-.021428,
.012142,-.020628,
.013128,-.019642,
.013928,-.0185,
.014518,-.017236,
.014878,-.015889,
.015,-.0145,
.015,.0145,
.014878,.015889,
.014518,.017236,
.013928,.0185,
.013128,.019642,
.012142,.020628,
.011,.021428,
.009736,.022018,
.008389,.022378,
.007,.0225,
-.007,.0225,
-.008389,.022378,
-.009736,.022018,
-.011,.021428,
-.012142,.020628,
-.013128,.019642,
-.013928,.0185,
-.014518,.017236,
-.014878,.015889,
-.015,.0145,
-.015,-.0145,
-.014878,-.015889,
-.014518,-.017236,
-.013928,-.0185,
-.013128,-.019642,
-.012142,-.020628,
-.011,-.021428,
-.009736,-.022018,
-.008389,-.022378,
-.007,-.0225,
.007,-.0225,
0.0*
%
%ADD65MACRO65*%
%AMMACRO62*
4,1,40,.014,-.008,
.014,.008,
.013939,.008695,
.013759,.009368,
.013464,.01,
.013064,.010571,
.012571,.011064,
.012,.011464,
.011368,.011759,
.010695,.011939,
.01,.012,
-.01,.012,
-.010695,.011939,
-.011368,.011759,
-.012,.011464,
-.012571,.011064,
-.013064,.010571,
-.013464,.01,
-.013759,.009368,
-.013939,.008695,
-.014,.008,
-.014,-.008,
-.013939,-.008695,
-.013759,-.009368,
-.013464,-.01,
-.013064,-.010571,
-.012571,-.011064,
-.012,-.011464,
-.011368,-.011759,
-.010695,-.011939,
-.01,-.012,
.01,-.012,
.010695,-.011939,
.011368,-.011759,
.012,-.011464,
.012571,-.011064,
.013064,-.010571,
.013464,-.01,
.013759,-.009368,
.013939,-.008695,
.014,-.008,
0.0*
%
%ADD62MACRO62*%
%AMMACRO32*
4,1,40,.007,-.011,
-.007,-.011,
-.007695,-.010939,
-.008368,-.010759,
-.009,-.010464,
-.009571,-.010064,
-.010064,-.009571,
-.010464,-.009,
-.010759,-.008368,
-.010939,-.007695,
-.011,-.007,
-.011,.007,
-.010939,.007695,
-.010759,.008368,
-.010464,.009,
-.010064,.009571,
-.009571,.010064,
-.009,.010464,
-.008368,.010759,
-.007695,.010939,
-.007,.011,
.007,.011,
.007695,.010939,
.008368,.010759,
.009,.010464,
.009571,.010064,
.010064,.009571,
.010464,.009,
.010759,.008368,
.010939,.007695,
.011,.007,
.011,-.007,
.010939,-.007695,
.010759,-.008368,
.010464,-.009,
.010064,-.009571,
.009571,-.010064,
.009,-.010464,
.008368,-.010759,
.007695,-.010939,
.007,-.011,
0.0*
%
%ADD32MACRO32*%
%AMMACRO17*
4,1,40,-.011,-.007,
-.011,.007,
-.010939,.007695,
-.010759,.008368,
-.010464,.009,
-.010064,.009571,
-.009571,.010064,
-.009,.010464,
-.008368,.010759,
-.007695,.010939,
-.007,.011,
.007,.011,
.007695,.010939,
.008368,.010759,
.009,.010464,
.009571,.010064,
.010064,.009571,
.010464,.009,
.010759,.008368,
.010939,.007695,
.011,.007,
.011,-.007,
.010939,-.007695,
.010759,-.008368,
.010464,-.009,
.010064,-.009571,
.009571,-.010064,
.009,-.010464,
.008368,-.010759,
.007695,-.010939,
.007,-.011,
-.007,-.011,
-.007695,-.010939,
-.008368,-.010759,
-.009,-.010464,
-.009571,-.010064,
-.010064,-.009571,
-.010464,-.009,
-.010759,-.008368,
-.010939,-.007695,
-.011,-.007,
0.0*
%
%ADD17MACRO17*%
%AMMACRO38*
4,1,40,-.012,-.008,
-.012,.008,
-.011939,.008695,
-.011759,.009368,
-.011464,.01,
-.011064,.010571,
-.010571,.011064,
-.01,.011464,
-.009368,.011759,
-.008695,.011939,
-.008,.012,
.008,.012,
.008695,.011939,
.009368,.011759,
.01,.011464,
.010571,.011064,
.011064,.010571,
.011464,.01,
.011759,.009368,
.011939,.008695,
.012,.008,
.012,-.008,
.011939,-.008695,
.011759,-.009368,
.011464,-.01,
.011064,-.010571,
.010571,-.011064,
.01,-.011464,
.009368,-.011759,
.008695,-.011939,
.008,-.012,
-.008,-.012,
-.008695,-.011939,
-.009368,-.011759,
-.01,-.011464,
-.010571,-.011064,
-.011064,-.010571,
-.011464,-.01,
-.011759,-.009368,
-.011939,-.008695,
-.012,-.008,
0.0*
%
%ADD38MACRO38*%
%AMMACRO40*
4,1,40,-.008,.012,
.008,.012,
.008695,.011939,
.009368,.011759,
.01,.011464,
.010571,.011064,
.011064,.010571,
.011464,.01,
.011759,.009368,
.011939,.008695,
.012,.008,
.012,-.008,
.011939,-.008695,
.011759,-.009368,
.011464,-.01,
.011064,-.010571,
.010571,-.011064,
.01,-.011464,
.009368,-.011759,
.008695,-.011939,
.008,-.012,
-.008,-.012,
-.008695,-.011939,
-.009368,-.011759,
-.01,-.011464,
-.010571,-.011064,
-.011064,-.010571,
-.011464,-.01,
-.011759,-.009368,
-.011939,-.008695,
-.012,-.008,
-.012,.008,
-.011939,.008695,
-.011759,.009368,
-.011464,.01,
-.011064,.010571,
-.010571,.011064,
-.01,.011464,
-.009368,.011759,
-.008695,.011939,
-.008,.012,
0.0*
%
%ADD40MACRO40*%
%AMMACRO72*
4,1,6,.0135,.025,
-.0065,.005,
-.0135,.005,
-.0135,-.005,
-.0065,-.005,
.0135,-.025,
.0135,.025,
0.0*
%
%ADD72MACRO72*%
%AMMACRO35*
4,1,40,-.013,.017,
.013,.017,
.013695,.016939,
.014368,.016759,
.015,.016464,
.015571,.016064,
.016064,.015571,
.016464,.015,
.016759,.014368,
.016939,.013695,
.017,.013,
.017,-.013,
.016939,-.013695,
.016759,-.014368,
.016464,-.015,
.016064,-.015571,
.015571,-.016064,
.015,-.016464,
.014368,-.016759,
.013695,-.016939,
.013,-.017,
-.013,-.017,
-.013695,-.016939,
-.014368,-.016759,
-.015,-.016464,
-.015571,-.016064,
-.016064,-.015571,
-.016464,-.015,
-.016759,-.014368,
-.016939,-.013695,
-.017,-.013,
-.017,.013,
-.016939,.013695,
-.016759,.014368,
-.016464,.015,
-.016064,.015571,
-.015571,.016064,
-.015,.016464,
-.014368,.016759,
-.013695,.016939,
-.013,.017,
0.0*
%
%ADD35MACRO35*%
%AMMACRO46*
4,1,40,.017,.013,
.017,-.013,
.016939,-.013695,
.016759,-.014368,
.016464,-.015,
.016064,-.015571,
.015571,-.016064,
.015,-.016464,
.014368,-.016759,
.013695,-.016939,
.013,-.017,
-.013,-.017,
-.013695,-.016939,
-.014368,-.016759,
-.015,-.016464,
-.015571,-.016064,
-.016064,-.015571,
-.016464,-.015,
-.016759,-.014368,
-.016939,-.013695,
-.017,-.013,
-.017,.013,
-.016939,.013695,
-.016759,.014368,
-.016464,.015,
-.016064,.015571,
-.015571,.016064,
-.015,.016464,
-.014368,.016759,
-.013695,.016939,
-.013,.017,
.013,.017,
.013695,.016939,
.014368,.016759,
.015,.016464,
.015571,.016064,
.016064,.015571,
.016464,.015,
.016759,.014368,
.016939,.013695,
.017,.013,
0.0*
%
%ADD46MACRO46*%
%AMMACRO33*
4,1,40,.007,-.011,
-.007,-.011,
-.007695,-.010939,
-.008368,-.010759,
-.009,-.010464,
-.009571,-.010064,
-.010064,-.009571,
-.010464,-.009,
-.010759,-.008368,
-.010939,-.007695,
-.011,-.007,
-.011,.007,
-.010939,.007695,
-.010759,.008368,
-.010464,.009,
-.010064,.009571,
-.009571,.010064,
-.009,.010464,
-.008368,.010759,
-.007695,.010939,
-.007,.011,
.007,.011,
.007695,.010939,
.008368,.010759,
.009,.010464,
.009571,.010064,
.010064,.009571,
.010464,.009,
.010759,.008368,
.010939,.007695,
.011,.007,
.011,-.007,
.010939,-.007695,
.010759,-.008368,
.010464,-.009,
.010064,-.009571,
.009571,-.010064,
.009,-.010464,
.008368,-.010759,
.007695,-.010939,
.007,-.011,
0.0*
%
%ADD33MACRO33*%
%AMMACRO18*
4,1,40,-.011,-.007,
-.011,.007,
-.010939,.007695,
-.010759,.008368,
-.010464,.009,
-.010064,.009571,
-.009571,.010064,
-.009,.010464,
-.008368,.010759,
-.007695,.010939,
-.007,.011,
.007,.011,
.007695,.010939,
.008368,.010759,
.009,.010464,
.009571,.010064,
.010064,.009571,
.010464,.009,
.010759,.008368,
.010939,.007695,
.011,.007,
.011,-.007,
.010939,-.007695,
.010759,-.008368,
.010464,-.009,
.010064,-.009571,
.009571,-.010064,
.009,-.010464,
.008368,-.010759,
.007695,-.010939,
.007,-.011,
-.007,-.011,
-.007695,-.010939,
-.008368,-.010759,
-.009,-.010464,
-.009571,-.010064,
-.010064,-.009571,
-.010464,-.009,
-.010759,-.008368,
-.010939,-.007695,
-.011,-.007,
0.0*
%
%ADD18MACRO18*%
%AMMACRO37*
4,1,40,-.012,-.008,
-.012,.008,
-.011939,.008695,
-.011759,.009368,
-.011464,.01,
-.011064,.010571,
-.010571,.011064,
-.01,.011464,
-.009368,.011759,
-.008695,.011939,
-.008,.012,
.008,.012,
.008695,.011939,
.009368,.011759,
.01,.011464,
.010571,.011064,
.011064,.010571,
.011464,.01,
.011759,.009368,
.011939,.008695,
.012,.008,
.012,-.008,
.011939,-.008695,
.011759,-.009368,
.011464,-.01,
.011064,-.010571,
.010571,-.011064,
.01,-.011464,
.009368,-.011759,
.008695,-.011939,
.008,-.012,
-.008,-.012,
-.008695,-.011939,
-.009368,-.011759,
-.01,-.011464,
-.010571,-.011064,
-.011064,-.010571,
-.011464,-.01,
-.011759,-.009368,
-.011939,-.008695,
-.012,-.008,
0.0*
%
%ADD37MACRO37*%
%AMMACRO39*
4,1,40,-.008,.012,
.008,.012,
.008695,.011939,
.009368,.011759,
.01,.011464,
.010571,.011064,
.011064,.010571,
.011464,.01,
.011759,.009368,
.011939,.008695,
.012,.008,
.012,-.008,
.011939,-.008695,
.011759,-.009368,
.011464,-.01,
.011064,-.010571,
.010571,-.011064,
.01,-.011464,
.009368,-.011759,
.008695,-.011939,
.008,-.012,
-.008,-.012,
-.008695,-.011939,
-.009368,-.011759,
-.01,-.011464,
-.010571,-.011064,
-.011064,-.010571,
-.011464,-.01,
-.011759,-.009368,
-.011939,-.008695,
-.012,-.008,
-.012,.008,
-.011939,.008695,
-.011759,.009368,
-.011464,.01,
-.011064,.010571,
-.010571,.011064,
-.01,.011464,
-.009368,.011759,
-.008695,.011939,
-.008,.012,
0.0*
%
%ADD39MACRO39*%
%AMMACRO36*
4,1,40,-.013,.017,
.013,.017,
.013695,.016939,
.014368,.016759,
.015,.016464,
.015571,.016064,
.016064,.015571,
.016464,.015,
.016759,.014368,
.016939,.013695,
.017,.013,
.017,-.013,
.016939,-.013695,
.016759,-.014368,
.016464,-.015,
.016064,-.015571,
.015571,-.016064,
.015,-.016464,
.014368,-.016759,
.013695,-.016939,
.013,-.017,
-.013,-.017,
-.013695,-.016939,
-.014368,-.016759,
-.015,-.016464,
-.015571,-.016064,
-.016064,-.015571,
-.016464,-.015,
-.016759,-.014368,
-.016939,-.013695,
-.017,-.013,
-.017,.013,
-.016939,.013695,
-.016759,.014368,
-.016464,.015,
-.016064,.015571,
-.015571,.016064,
-.015,.016464,
-.014368,.016759,
-.013695,.016939,
-.013,.017,
0.0*
%
%ADD36MACRO36*%
%AMMACRO47*
4,1,40,.017,.013,
.017,-.013,
.016939,-.013695,
.016759,-.014368,
.016464,-.015,
.016064,-.015571,
.015571,-.016064,
.015,-.016464,
.014368,-.016759,
.013695,-.016939,
.013,-.017,
-.013,-.017,
-.013695,-.016939,
-.014368,-.016759,
-.015,-.016464,
-.015571,-.016064,
-.016064,-.015571,
-.016464,-.015,
-.016759,-.014368,
-.016939,-.013695,
-.017,-.013,
-.017,.013,
-.016939,.013695,
-.016759,.014368,
-.016464,.015,
-.016064,.015571,
-.015571,.016064,
-.015,.016464,
-.014368,.016759,
-.013695,.016939,
-.013,.017,
.013,.017,
.013695,.016939,
.014368,.016759,
.015,.016464,
.015571,.016064,
.016064,.015571,
.016464,.015,
.016759,.014368,
.016939,.013695,
.017,.013,
0.0*
%
%ADD47MACRO47*%
%ADD44R,.06X.014*%
%ADD67R,.014X.06*%
%ADD28C,.13*%
%ADD58R,.05X.065*%
%ADD53O,.06X.084*%
%ADD27O,.268X.134*%
%ADD66O,.126X.189*%
%ADD34R,.048X.016*%
%ADD22R,.045X.055*%
%ADD49R,.016X.048*%
%ADD31R,.055X.045*%
%ADD48C,.256*%
%ADD14C,.375*%
%AMMACRO61*
4,1,40,-.014,.008,
-.014,-.008,
-.013939,-.008695,
-.013759,-.009368,
-.013464,-.01,
-.013064,-.010571,
-.012571,-.011064,
-.012,-.011464,
-.011368,-.011759,
-.010695,-.011939,
-.01,-.012,
.01,-.012,
.010695,-.011939,
.011368,-.011759,
.012,-.011464,
.012571,-.011064,
.013064,-.010571,
.013464,-.01,
.013759,-.009368,
.013939,-.008695,
.014,-.008,
.014,.008,
.013939,.008695,
.013759,.009368,
.013464,.01,
.013064,.010571,
.012571,.011064,
.012,.011464,
.011368,.011759,
.010695,.011939,
.01,.012,
-.01,.012,
-.010695,.011939,
-.011368,.011759,
-.012,.011464,
-.012571,.011064,
-.013064,.010571,
-.013464,.01,
-.013759,.009368,
-.013939,.008695,
-.014,.008,
0.0*
%
%ADD61MACRO61*%
%AMMACRO60*
4,1,40,-.0225,-.007,
-.022378,-.008389,
-.022018,-.009736,
-.021428,-.011,
-.020628,-.012142,
-.019642,-.013128,
-.0185,-.013928,
-.017236,-.014518,
-.015889,-.014878,
-.0145,-.015,
.0145,-.015,
.015889,-.014878,
.017236,-.014518,
.0185,-.013928,
.019642,-.013128,
.020628,-.012142,
.021428,-.011,
.022018,-.009736,
.022378,-.008389,
.0225,-.007,
.0225,.007,
.022378,.008389,
.022018,.009736,
.021428,.011,
.020628,.012142,
.019642,.013128,
.0185,.013928,
.017236,.014518,
.015889,.014878,
.0145,.015,
-.0145,.015,
-.015889,.014878,
-.017236,.014518,
-.0185,.013928,
-.019642,.013128,
-.020628,.012142,
-.021428,.011,
-.022018,.009736,
-.022378,.008389,
-.0225,.007,
-.0225,-.007,
0.0*
%
%ADD60MACRO60*%
%AMMACRO55*
4,1,40,-.007,.0225,
-.008389,.022378,
-.009736,.022018,
-.011,.021428,
-.012142,.020628,
-.013128,.019642,
-.013928,.0185,
-.014518,.017236,
-.014878,.015889,
-.015,.0145,
-.015,-.0145,
-.014878,-.015889,
-.014518,-.017236,
-.013928,-.0185,
-.013128,-.019642,
-.012142,-.020628,
-.011,-.021428,
-.009736,-.022018,
-.008389,-.022378,
-.007,-.0225,
.007,-.0225,
.008389,-.022378,
.009736,-.022018,
.011,-.021428,
.012142,-.020628,
.013128,-.019642,
.013928,-.0185,
.014518,-.017236,
.014878,-.015889,
.015,-.0145,
.015,.0145,
.014878,.015889,
.014518,.017236,
.013928,.0185,
.013128,.019642,
.012142,.020628,
.011,.021428,
.009736,.022018,
.008389,.022378,
.007,.0225,
-.007,.0225,
0.0*
%
%ADD55MACRO55*%
%AMMACRO30*
4,1,40,.012,.008,
.012,-.008,
.011939,-.008695,
.011759,-.009368,
.011464,-.01,
.011064,-.010571,
.010571,-.011064,
.01,-.011464,
.009368,-.011759,
.008695,-.011939,
.008,-.012,
-.008,-.012,
-.008695,-.011939,
-.009368,-.011759,
-.01,-.011464,
-.010571,-.011064,
-.011064,-.010571,
-.011464,-.01,
-.011759,-.009368,
-.011939,-.008695,
-.012,-.008,
-.012,.008,
-.011939,.008695,
-.011759,.009368,
-.011464,.01,
-.011064,.010571,
-.010571,.011064,
-.01,.011464,
-.009368,.011759,
-.008695,.011939,
-.008,.012,
.008,.012,
.008695,.011939,
.009368,.011759,
.01,.011464,
.010571,.011064,
.011064,.010571,
.011464,.01,
.011759,.009368,
.011939,.008695,
.012,.008,
0.0*
%
%ADD30MACRO30*%
%AMMACRO19*
4,1,40,-.007,.011,
.007,.011,
.007695,.010939,
.008368,.010759,
.009,.010464,
.009571,.010064,
.010064,.009571,
.010464,.009,
.010759,.008368,
.010939,.007695,
.011,.007,
.011,-.007,
.010939,-.007695,
.010759,-.008368,
.010464,-.009,
.010064,-.009571,
.009571,-.010064,
.009,-.010464,
.008368,-.010759,
.007695,-.010939,
.007,-.011,
-.007,-.011,
-.007695,-.010939,
-.008368,-.010759,
-.009,-.010464,
-.009571,-.010064,
-.010064,-.009571,
-.010464,-.009,
-.010759,-.008368,
-.010939,-.007695,
-.011,-.007,
-.011,.007,
-.010939,.007695,
-.010759,.008368,
-.010464,.009,
-.010064,.009571,
-.009571,.010064,
-.009,.010464,
-.008368,.010759,
-.007695,.010939,
-.007,.011,
0.0*
%
%ADD19MACRO19*%
%AMMACRO16*
4,1,40,.008,-.012,
-.008,-.012,
-.008695,-.011939,
-.009368,-.011759,
-.01,-.011464,
-.010571,-.011064,
-.011064,-.010571,
-.011464,-.01,
-.011759,-.009368,
-.011939,-.008695,
-.012,-.008,
-.012,.008,
-.011939,.008695,
-.011759,.009368,
-.011464,.01,
-.011064,.010571,
-.010571,.011064,
-.01,.011464,
-.009368,.011759,
-.008695,.011939,
-.008,.012,
.008,.012,
.008695,.011939,
.009368,.011759,
.01,.011464,
.010571,.011064,
.011064,.010571,
.011464,.01,
.011759,.009368,
.011939,.008695,
.012,.008,
.012,-.008,
.011939,-.008695,
.011759,-.009368,
.011464,-.01,
.011064,-.010571,
.010571,-.011064,
.01,-.011464,
.009368,-.011759,
.008695,-.011939,
.008,-.012,
0.0*
%
%ADD16MACRO16*%
%AMMACRO41*
4,1,40,.011,.007,
.011,-.007,
.010939,-.007695,
.010759,-.008368,
.010464,-.009,
.010064,-.009571,
.009571,-.010064,
.009,-.010464,
.008368,-.010759,
.007695,-.010939,
.007,-.011,
-.007,-.011,
-.007695,-.010939,
-.008368,-.010759,
-.009,-.010464,
-.009571,-.010064,
-.010064,-.009571,
-.010464,-.009,
-.010759,-.008368,
-.010939,-.007695,
-.011,-.007,
-.011,.007,
-.010939,.007695,
-.010759,.008368,
-.010464,.009,
-.010064,.009571,
-.009571,.010064,
-.009,.010464,
-.008368,.010759,
-.007695,.010939,
-.007,.011,
.007,.011,
.007695,.010939,
.008368,.010759,
.009,.010464,
.009571,.010064,
.010064,.009571,
.010464,.009,
.010759,.008368,
.010939,.007695,
.011,.007,
0.0*
%
%ADD41MACRO41*%
%AMMACRO25*
4,1,40,-.017,-.013,
-.017,.013,
-.016939,.013695,
-.016759,.014368,
-.016464,.015,
-.016064,.015571,
-.015571,.016064,
-.015,.016464,
-.014368,.016759,
-.013695,.016939,
-.013,.017,
.013,.017,
.013695,.016939,
.014368,.016759,
.015,.016464,
.015571,.016064,
.016064,.015571,
.016464,.015,
.016759,.014368,
.016939,.013695,
.017,.013,
.017,-.013,
.016939,-.013695,
.016759,-.014368,
.016464,-.015,
.016064,-.015571,
.015571,-.016064,
.015,-.016464,
.014368,-.016759,
.013695,-.016939,
.013,-.017,
-.013,-.017,
-.013695,-.016939,
-.014368,-.016759,
-.015,-.016464,
-.015571,-.016064,
-.016064,-.015571,
-.016464,-.015,
-.016759,-.014368,
-.016939,-.013695,
-.017,-.013,
0.0*
%
%ADD25MACRO25*%
%AMMACRO23*
4,1,40,.013,-.017,
-.013,-.017,
-.013695,-.016939,
-.014368,-.016759,
-.015,-.016464,
-.015571,-.016064,
-.016064,-.015571,
-.016464,-.015,
-.016759,-.014368,
-.016939,-.013695,
-.017,-.013,
-.017,.013,
-.016939,.013695,
-.016759,.014368,
-.016464,.015,
-.016064,.015571,
-.015571,.016064,
-.015,.016464,
-.014368,.016759,
-.013695,.016939,
-.013,.017,
.013,.017,
.013695,.016939,
.014368,.016759,
.015,.016464,
.015571,.016064,
.016064,.015571,
.016464,.015,
.016759,.014368,
.016939,.013695,
.017,.013,
.017,-.013,
.016939,-.013695,
.016759,-.014368,
.016464,-.015,
.016064,-.015571,
.015571,-.016064,
.015,-.016464,
.014368,-.016759,
.013695,-.016939,
.013,-.017,
0.0*
%
%ADD23MACRO23*%
%AMMACRO71*
4,1,6,.0135,.005,
.0065,.005,
-.0135,.025,
-.0135,-.025,
.0065,-.005,
.0135,-.005,
.0135,.005,
0.0*
%
%ADD71MACRO71*%
%AMMACRO29*
4,1,40,.012,.008,
.012,-.008,
.011939,-.008695,
.011759,-.009368,
.011464,-.01,
.011064,-.010571,
.010571,-.011064,
.01,-.011464,
.009368,-.011759,
.008695,-.011939,
.008,-.012,
-.008,-.012,
-.008695,-.011939,
-.009368,-.011759,
-.01,-.011464,
-.010571,-.011064,
-.011064,-.010571,
-.011464,-.01,
-.011759,-.009368,
-.011939,-.008695,
-.012,-.008,
-.012,.008,
-.011939,.008695,
-.011759,.009368,
-.011464,.01,
-.011064,.010571,
-.010571,.011064,
-.01,.011464,
-.009368,.011759,
-.008695,.011939,
-.008,.012,
.008,.012,
.008695,.011939,
.009368,.011759,
.01,.011464,
.010571,.011064,
.011064,.010571,
.011464,.01,
.011759,.009368,
.011939,.008695,
.012,.008,
0.0*
%
%ADD29MACRO29*%
%AMMACRO20*
4,1,40,-.007,.011,
.007,.011,
.007695,.010939,
.008368,.010759,
.009,.010464,
.009571,.010064,
.010064,.009571,
.010464,.009,
.010759,.008368,
.010939,.007695,
.011,.007,
.011,-.007,
.010939,-.007695,
.010759,-.008368,
.010464,-.009,
.010064,-.009571,
.009571,-.010064,
.009,-.010464,
.008368,-.010759,
.007695,-.010939,
.007,-.011,
-.007,-.011,
-.007695,-.010939,
-.008368,-.010759,
-.009,-.010464,
-.009571,-.010064,
-.010064,-.009571,
-.010464,-.009,
-.010759,-.008368,
-.010939,-.007695,
-.011,-.007,
-.011,.007,
-.010939,.007695,
-.010759,.008368,
-.010464,.009,
-.010064,.009571,
-.009571,.010064,
-.009,.010464,
-.008368,.010759,
-.007695,.010939,
-.007,.011,
0.0*
%
%ADD20MACRO20*%
%AMMACRO15*
4,1,40,.008,-.012,
-.008,-.012,
-.008695,-.011939,
-.009368,-.011759,
-.01,-.011464,
-.010571,-.011064,
-.011064,-.010571,
-.011464,-.01,
-.011759,-.009368,
-.011939,-.008695,
-.012,-.008,
-.012,.008,
-.011939,.008695,
-.011759,.009368,
-.011464,.01,
-.011064,.010571,
-.010571,.011064,
-.01,.011464,
-.009368,.011759,
-.008695,.011939,
-.008,.012,
.008,.012,
.008695,.011939,
.009368,.011759,
.01,.011464,
.010571,.011064,
.011064,.010571,
.011464,.01,
.011759,.009368,
.011939,.008695,
.012,.008,
.012,-.008,
.011939,-.008695,
.011759,-.009368,
.011464,-.01,
.011064,-.010571,
.010571,-.011064,
.01,-.011464,
.009368,-.011759,
.008695,-.011939,
.008,-.012,
0.0*
%
%ADD15MACRO15*%
%ADD73C,.006*%
G75*
%LPD*%
G75*
G54D10*
X61024Y34449D03*
X33464D03*
X56102Y24606D03*
X38386D03*
X108268Y44292D03*
X80708D03*
X103346Y34449D03*
X85630D03*
G54D20*
X45906Y532622D03*
X38465Y532638D03*
X45985Y555153D03*
X38485D03*
X45906Y538249D03*
X38358Y538254D03*
X45906Y543876D03*
X38458Y543881D03*
X45906Y526995D03*
X38475D03*
X45906Y521269D03*
X38432Y521271D03*
X45985Y549526D03*
X38503Y549508D03*
X45985Y560879D03*
X38400Y560900D03*
X55100Y575850D03*
X50756Y571795D03*
X137000Y479700D03*
Y483900D03*
X112772Y497305D03*
X124800Y610500D03*
X126400Y630800D03*
Y634900D03*
Y639000D03*
X196800Y489500D03*
X171500Y530700D03*
X156889Y520812D03*
X184280Y520045D03*
X183838Y536101D03*
X174686Y513171D03*
X147103Y509389D03*
X193700Y528500D03*
X211800Y634500D03*
X172087Y587147D03*
X184710Y617688D03*
X186704Y636190D03*
X194170Y636210D03*
X148300Y590500D03*
X203600Y642300D03*
X187845Y642681D03*
X195700Y642800D03*
X216300Y471100D03*
X225025Y484151D03*
X249000Y543600D03*
X239520Y562521D03*
X216053Y528088D03*
X222108Y637894D03*
X224148Y581666D03*
X235500Y597500D03*
X265300Y588500D03*
X249500Y571100D03*
Y567100D03*
X241730Y571032D03*
X241430Y566732D03*
X293120Y561123D03*
X344200Y574900D03*
X314622Y606283D03*
X304400Y661300D03*
X373800Y31000D03*
X362300Y574900D03*
X357533Y673696D03*
X357400Y665580D03*
X458260Y25990D03*
X490260Y37883D03*
X438000Y37800D03*
X517890Y77700D03*
X696344Y480189D03*
X751579Y538718D03*
X766794Y540231D03*
X759305Y538797D03*
X828039Y340820D03*
X813496Y428321D03*
G54D11*
G01X-36569Y-23804D02*
Y-103804D01*
G01D02*
X1258031D01*
G01X-40569Y-7804D02*
G02I-12000J0D01*
G01X-45719D02*
G02I-6850J0D01*
G01X-52569Y-23804D02*
Y8196D01*
G01X-36569Y-23804D02*
X1258031D01*
G01X-36569Y-59304D02*
X1258031D01*
G01X-36569Y-7804D02*
X-68569D01*
G01X470531Y-23804D02*
Y-103804D01*
G01X608031Y-23804D02*
Y-103804D01*
G01X723031Y-23804D02*
Y-103804D01*
G01X890531Y-23804D02*
Y-103804D01*
G01X1060531Y-23804D02*
Y-103804D01*
G01X1258031Y-23804D02*
Y-103804D01*
G01X1286031Y-7804D02*
G02I-12000J0D01*
G01X1280881D02*
G02I-6850J0D01*
G01X1274031Y-23804D02*
Y8196D01*
G01X1290031Y-7804D02*
X1258031D01*
X66435Y8514D03*
X61435D03*
X56435D03*
X51435D03*
X46435D03*
X41435D03*
X36435D03*
X31435D03*
X26435D03*
X21435D03*
X16435D03*
X8514Y10593D03*
Y15593D03*
Y20593D03*
Y25593D03*
Y30593D03*
Y35593D03*
Y40593D03*
Y45593D03*
Y50593D03*
Y55593D03*
Y60593D03*
Y65593D03*
Y70593D03*
Y75593D03*
Y80593D03*
Y85593D03*
Y90593D03*
Y95593D03*
Y100593D03*
Y105593D03*
Y110593D03*
Y115593D03*
Y120593D03*
Y125593D03*
Y130593D03*
Y135593D03*
Y140593D03*
Y145593D03*
Y150593D03*
Y155593D03*
Y160593D03*
Y165593D03*
Y170593D03*
Y175593D03*
Y180593D03*
Y185593D03*
Y190593D03*
Y195593D03*
Y200593D03*
Y205593D03*
Y210593D03*
Y215593D03*
Y220593D03*
Y225593D03*
Y230593D03*
Y235593D03*
Y240593D03*
Y245593D03*
Y250593D03*
Y255593D03*
Y260593D03*
Y265593D03*
Y270593D03*
Y275593D03*
Y280593D03*
Y285593D03*
Y290593D03*
Y295593D03*
Y300593D03*
Y305593D03*
Y310593D03*
Y315593D03*
Y320593D03*
Y325593D03*
Y330593D03*
Y335593D03*
Y340593D03*
Y345593D03*
Y350593D03*
Y355593D03*
Y360593D03*
Y365593D03*
Y370593D03*
Y375593D03*
Y380593D03*
Y385593D03*
Y390593D03*
Y395593D03*
Y400593D03*
Y405593D03*
Y410593D03*
Y415593D03*
Y420593D03*
Y425593D03*
Y430593D03*
Y435593D03*
Y440593D03*
Y445593D03*
Y450593D03*
Y455593D03*
Y460593D03*
Y465593D03*
Y470593D03*
Y475593D03*
Y480593D03*
Y485593D03*
Y490593D03*
Y495593D03*
Y500593D03*
Y505593D03*
Y510593D03*
Y515593D03*
Y520593D03*
Y525593D03*
Y530593D03*
Y535593D03*
Y540593D03*
Y545593D03*
Y550593D03*
Y555593D03*
Y560593D03*
Y565593D03*
Y570593D03*
Y575593D03*
Y580593D03*
Y585593D03*
Y590593D03*
Y595593D03*
Y600593D03*
Y605593D03*
Y610593D03*
Y615593D03*
Y620593D03*
Y625593D03*
Y630593D03*
Y635593D03*
Y640593D03*
Y645593D03*
Y650593D03*
Y655593D03*
Y660593D03*
Y665593D03*
Y670593D03*
Y675593D03*
Y680593D03*
Y685593D03*
Y690593D03*
Y695593D03*
Y700593D03*
Y705593D03*
Y710593D03*
Y715593D03*
Y720593D03*
X9942Y725256D03*
X12178Y729728D03*
X14414Y734200D03*
X16650Y738672D03*
X18886Y743144D03*
X21122Y747617D03*
X23358Y752089D03*
X111683Y63266D03*
Y58266D03*
Y23266D03*
Y18266D03*
Y13266D03*
X111435Y8514D03*
X106435D03*
X101435D03*
X96435D03*
X91435D03*
X86435D03*
X81435D03*
X76435D03*
X71435D03*
X111683Y118266D03*
Y113266D03*
Y108266D03*
Y103266D03*
Y98266D03*
Y93266D03*
Y88266D03*
Y83266D03*
Y78266D03*
Y73266D03*
Y68266D03*
Y203266D03*
Y198266D03*
Y193266D03*
Y188266D03*
Y183266D03*
Y178266D03*
Y173266D03*
Y168266D03*
Y163266D03*
Y158266D03*
Y153266D03*
Y148266D03*
Y278266D03*
Y273266D03*
Y268266D03*
Y263266D03*
Y258266D03*
Y253266D03*
Y248266D03*
Y243266D03*
Y238266D03*
Y233266D03*
Y228266D03*
Y223266D03*
Y218266D03*
Y213266D03*
Y208266D03*
Y348266D03*
Y343266D03*
Y338266D03*
Y333266D03*
Y328266D03*
Y323266D03*
Y318266D03*
Y313266D03*
Y308266D03*
Y303266D03*
Y298266D03*
Y293266D03*
Y288266D03*
Y283266D03*
Y418266D03*
Y413266D03*
Y408266D03*
Y403266D03*
Y398266D03*
Y393266D03*
Y388266D03*
Y383266D03*
Y378266D03*
Y373266D03*
Y368266D03*
Y363266D03*
Y358266D03*
Y353266D03*
X103940Y635460D03*
X76118Y625275D03*
X81118D03*
X86300Y703200D03*
X99337Y683756D03*
Y678756D03*
Y673756D03*
X86300Y708000D03*
X95200Y667500D03*
X90400D03*
X85600D03*
X76549Y680547D03*
Y675547D03*
X81549Y680547D03*
Y675547D03*
X134223Y691027D03*
X122335Y660582D03*
Y655782D03*
X76395Y755266D03*
X81395D03*
X86395D03*
X91395D03*
X96395D03*
X101395D03*
X106395D03*
X111395D03*
X116395D03*
X121395D03*
X126395D03*
X131395D03*
X136395D03*
X141395D03*
X108928Y744775D03*
X113928D03*
X118928D03*
X123928D03*
X103928D03*
X98928D03*
X93928D03*
X83125Y719240D03*
Y724040D03*
X196700Y704985D03*
X201700D03*
X206700D03*
X211700D03*
X191700D03*
X146395Y755266D03*
X151395D03*
X156395D03*
X161395D03*
X166395D03*
X171395D03*
X176395D03*
X181395D03*
X186395D03*
X191395D03*
X196395D03*
X201395D03*
X206395D03*
X211395D03*
X155400Y717700D03*
X221700Y704985D03*
X226700D03*
X216700D03*
X216395Y755266D03*
X221395D03*
X226395D03*
X231395D03*
X236395D03*
X241395D03*
X246395D03*
X251395D03*
X256395D03*
X261395D03*
X266395D03*
X271395D03*
X276395D03*
X281395D03*
X249200Y733700D03*
Y728700D03*
Y723700D03*
Y718700D03*
Y738500D03*
X330546Y8514D03*
X325546D03*
X320546D03*
X315546D03*
X310546D03*
X305546D03*
X300546D03*
X296034Y9002D03*
Y14002D03*
Y19002D03*
Y24002D03*
Y29002D03*
Y34002D03*
Y39002D03*
Y44002D03*
Y49002D03*
Y54002D03*
Y59002D03*
Y64002D03*
Y69002D03*
Y74002D03*
Y79002D03*
Y84002D03*
Y89002D03*
Y94002D03*
Y99002D03*
Y104002D03*
Y109002D03*
Y114002D03*
Y119002D03*
Y124002D03*
Y129002D03*
Y134002D03*
Y139002D03*
X334782Y184928D03*
X321182Y202574D03*
Y197774D03*
X305882Y195474D03*
X305382Y190174D03*
X334882Y195478D03*
Y200478D03*
Y190478D03*
X335061Y222578D03*
X335100Y218378D03*
X323492Y214234D03*
X305862Y210014D03*
X335000Y621200D03*
Y615400D03*
Y610200D03*
X325600Y640100D03*
X330400D03*
X335200D03*
X322000Y653081D03*
X312400D03*
X317200D03*
X307600D03*
X298700Y674600D03*
X303700D03*
X286395Y755266D03*
X291395D03*
X296395D03*
X301395D03*
X306395D03*
X311395D03*
X316395D03*
X321395D03*
X326395D03*
X331395D03*
X336395D03*
X315520Y711720D03*
X320320D03*
X325120D03*
X305559Y720973D03*
X310559D03*
X305559Y725973D03*
X310559D03*
X299500Y725400D03*
X373073Y201889D03*
X399754Y706071D03*
X389168Y743572D03*
X391404Y739100D03*
X393640Y734628D03*
X395876Y730156D03*
X398112Y725684D03*
X399754Y716071D03*
Y711071D03*
X435000Y29000D03*
X438500Y25500D03*
Y32500D03*
X491500Y71600D03*
X496500D03*
X491500Y76600D03*
X496500D03*
X556510Y53626D03*
X516693Y46345D03*
X521493D03*
X516693Y41545D03*
X521493D03*
Y36745D03*
X516693D03*
X521493Y31945D03*
X526530Y43775D03*
X516693Y31945D03*
X567700Y28240D03*
X548550Y76480D03*
X525000Y76300D03*
X525200Y80900D03*
X556710Y64726D03*
X543750Y76480D03*
X506500Y76600D03*
X501500D03*
Y71600D03*
X608847Y34607D03*
X614032Y33307D03*
X621747Y63307D03*
X626647Y77507D03*
Y72507D03*
Y67507D03*
X593017Y69796D03*
X588217Y74596D03*
Y69796D03*
X576624Y193205D03*
Y198205D03*
Y203205D03*
Y208205D03*
Y213205D03*
Y223205D03*
Y228205D03*
Y233205D03*
Y238205D03*
Y243205D03*
Y248205D03*
Y253205D03*
Y258205D03*
Y263205D03*
Y268205D03*
Y273205D03*
Y278205D03*
Y333205D03*
Y338205D03*
Y343205D03*
Y348205D03*
Y353205D03*
Y358205D03*
Y363205D03*
Y368205D03*
Y373205D03*
Y378205D03*
Y383205D03*
Y388205D03*
Y393205D03*
Y398205D03*
Y403205D03*
Y408205D03*
Y413205D03*
Y418205D03*
Y423205D03*
Y428205D03*
Y433205D03*
Y438205D03*
Y443205D03*
Y448205D03*
Y498205D03*
Y503205D03*
Y508205D03*
Y513205D03*
Y518205D03*
Y523205D03*
Y528205D03*
Y533205D03*
Y538205D03*
Y543205D03*
Y548205D03*
Y553205D03*
Y558205D03*
Y563205D03*
Y568205D03*
Y573205D03*
Y578205D03*
Y583205D03*
Y588205D03*
X578710Y592712D03*
X580946Y597184D03*
X583182Y601656D03*
X585418Y606129D03*
X587654Y610601D03*
X635975Y621407D03*
X640975D03*
X715546Y8514D03*
X710546D03*
X705546D03*
X700546D03*
X695546D03*
X668847Y27107D03*
X663847D03*
X658847D03*
X653847D03*
X653601Y46761D03*
X658601D03*
X653601Y51761D03*
X658601D03*
X663601Y46761D03*
Y51761D03*
X668601Y46761D03*
Y51761D03*
X700065Y135985D03*
Y125985D03*
Y115985D03*
X710065D03*
Y125985D03*
Y135985D03*
X649590Y114036D03*
X700065Y155985D03*
X710065D03*
Y145985D03*
X696159Y225829D03*
X698909Y278104D03*
X700065Y265985D03*
Y255985D03*
Y245985D03*
Y235985D03*
X710065D03*
Y245985D03*
Y255985D03*
Y265985D03*
X709625Y275991D03*
X710065Y325985D03*
Y315985D03*
X711574Y285985D03*
X708307Y295429D03*
X710065Y305985D03*
Y335985D03*
Y345985D03*
X700065Y385985D03*
Y395985D03*
Y405985D03*
Y415985D03*
X710065Y375985D03*
Y355985D03*
Y365985D03*
Y455985D03*
X684399Y466984D03*
Y471984D03*
X663500Y484000D03*
Y489000D03*
Y494000D03*
X692282Y476720D03*
X689875Y464586D03*
X698275Y438305D03*
X683100Y485200D03*
X679832Y494100D03*
Y489100D03*
X679100Y483300D03*
X674900D03*
X674832Y489100D03*
Y494100D03*
X682800Y480700D03*
X693392Y520482D03*
X683392D03*
X688392D03*
X705080Y521247D03*
X694272Y495786D03*
X645975Y621407D03*
X650975D03*
X655975D03*
X660975D03*
X665975D03*
X670975D03*
X675975D03*
X680975D03*
X685975D03*
X690975D03*
X695975D03*
X700975D03*
X705975D03*
X710975D03*
X715975D03*
X785546Y8514D03*
X780546D03*
X775546D03*
X770546D03*
X765546D03*
X760546D03*
X755546D03*
X750546D03*
X745546D03*
X740546D03*
X735546D03*
X730546D03*
X725546D03*
X720546D03*
X770065Y55985D03*
Y65985D03*
Y75985D03*
X750065Y85985D03*
X770065D03*
X760065D03*
X740065D03*
X730065Y95985D03*
X760065D03*
X780065D03*
X770065D03*
Y105985D03*
X780065D03*
Y115985D03*
X730065Y135985D03*
Y125985D03*
Y115985D03*
Y105985D03*
X750065Y95985D03*
X740065D03*
X750065Y105985D03*
X760065D03*
X740065D03*
X750065Y115985D03*
X760065D03*
X770065D03*
X740065D03*
X750065Y125985D03*
X760065D03*
X770065D03*
X780065D03*
X740065D03*
X750065Y135985D03*
X760065D03*
X770065D03*
X780065D03*
X740065D03*
X720065Y105985D03*
Y115985D03*
Y125985D03*
Y135985D03*
Y155985D03*
X780065D03*
X730065D03*
Y145985D03*
X750065D03*
X760065D03*
X770065D03*
X780065D03*
X740065D03*
X750065Y155985D03*
X760065D03*
X770065D03*
X740065D03*
X750065Y165985D03*
X760065D03*
X770065D03*
X740065D03*
X750065Y175985D03*
X760065D03*
X770065D03*
X740065D03*
X750065Y185985D03*
X760065D03*
X770065D03*
X740065D03*
X750065Y195985D03*
X760065D03*
X770065D03*
X740065D03*
X750065Y205985D03*
X760065D03*
X770065D03*
X740065D03*
X720065Y145985D03*
X730065Y215985D03*
X773469Y277001D03*
X780065Y275985D03*
X787817Y275879D03*
X750065Y215985D03*
X760065D03*
X770065D03*
X780065D03*
X740065D03*
X780065Y265985D03*
Y255985D03*
Y245985D03*
Y235985D03*
Y225985D03*
X770065Y265985D03*
Y255985D03*
Y245985D03*
Y235985D03*
Y225985D03*
X763133Y275881D03*
X759790Y263326D03*
X760065Y255985D03*
Y245985D03*
Y235985D03*
Y225985D03*
X750065Y275985D03*
Y265985D03*
Y255985D03*
Y245985D03*
Y235985D03*
Y225985D03*
X741608Y277171D03*
X740065Y265985D03*
Y255985D03*
Y245985D03*
Y235985D03*
Y225985D03*
X730830Y276087D03*
X730065Y265985D03*
Y255985D03*
X731766Y246017D03*
X730065Y235985D03*
X730190Y223549D03*
X720237Y223228D03*
X720065Y235985D03*
X721766Y246017D03*
X720065Y255985D03*
Y265985D03*
X718617Y275736D03*
X770065Y335985D03*
X760065D03*
X720065Y325985D03*
X760065D03*
X750065D03*
X740065D03*
X730065D03*
X720065Y315985D03*
X780065Y285985D03*
X770065D03*
X760065D03*
X750065Y295985D03*
X760065D03*
X770065D03*
X780065D03*
Y305985D03*
Y315985D03*
Y325985D03*
Y335985D03*
Y345985D03*
X770065Y305985D03*
Y315985D03*
Y325985D03*
Y345985D03*
X760065Y305985D03*
Y315985D03*
Y345985D03*
X750065Y305985D03*
Y315985D03*
Y335985D03*
Y345985D03*
X740065Y305985D03*
Y315985D03*
Y335985D03*
Y345985D03*
X730065D03*
Y335985D03*
Y315985D03*
X752500Y286000D03*
X740065Y295985D03*
X741000Y286000D03*
X730065Y305985D03*
X729486Y296094D03*
X729294Y285987D03*
X721574Y285985D03*
X719049Y296011D03*
X720065Y305985D03*
Y335985D03*
Y345985D03*
X750065Y415985D03*
X760065D03*
X770065D03*
X780065D03*
X730065D03*
X740065D03*
X750065Y405985D03*
X760065D03*
X770065D03*
X780065D03*
X730065D03*
X740065D03*
X780065Y395985D03*
X770065D03*
X760065D03*
X750065D03*
X740065D03*
X730065D03*
X720065Y375985D03*
X730065Y365985D03*
Y375985D03*
Y385985D03*
X750065D03*
X760065D03*
X770065D03*
X780065D03*
X740065D03*
X750065Y375985D03*
X760065D03*
X770065D03*
X780065D03*
X740065D03*
X750065Y365985D03*
X760065D03*
X770065D03*
X780065D03*
X740065D03*
X780065Y355985D03*
X770065D03*
X760065D03*
X750065D03*
X740065D03*
X730065D03*
X720065D03*
Y365985D03*
Y455985D03*
Y465985D03*
X750065D03*
X760065D03*
X770065D03*
X780065D03*
X730065D03*
X740065D03*
X780065Y455985D03*
X770065D03*
X760065D03*
X750065D03*
X740065D03*
X730065D03*
X750065Y445985D03*
X760065D03*
X770065D03*
X780065D03*
X730065D03*
X740065D03*
X750065Y435985D03*
X760065D03*
X770065D03*
X780065D03*
X740065D03*
X750065Y425985D03*
X760065D03*
X770065D03*
X780065D03*
X736217Y493664D03*
X776658Y489380D03*
X771658D03*
X781658D03*
Y494380D03*
X741217Y493664D03*
X776658Y494380D03*
X771658D03*
X784604Y519082D03*
X758512Y534430D03*
X747107Y536580D03*
X739334Y524156D03*
X752602Y517850D03*
X736580Y507734D03*
X788015Y507785D03*
X783015D03*
X747602Y517850D03*
X731580Y507734D03*
X716578Y509762D03*
X721590Y511659D03*
X726590D03*
X720975Y621407D03*
X725975D03*
X730975D03*
X735975D03*
X740975D03*
X745975D03*
X750975D03*
X755975D03*
X760975D03*
X765975D03*
X770975D03*
X775975D03*
X780975D03*
X785975D03*
X850546Y8514D03*
X845546D03*
X840546D03*
X835546D03*
X830546D03*
X825546D03*
X820546D03*
X815546D03*
X810546D03*
X805546D03*
X800546D03*
X795546D03*
X790546D03*
X820065Y105985D03*
Y135985D03*
Y125985D03*
Y115985D03*
X810065Y135985D03*
Y125985D03*
Y115985D03*
X790065Y105985D03*
X800065Y115985D03*
X790065D03*
Y125985D03*
X800065D03*
Y135985D03*
X790065D03*
X853436Y108917D03*
Y113717D03*
X853435Y90260D03*
Y95060D03*
X820065Y155985D03*
X810065D03*
X800065D03*
X790065D03*
X820065Y145985D03*
X810065D03*
X790065D03*
X800065D03*
X820313Y276188D03*
X810065Y275985D03*
X800065D03*
X820065Y265985D03*
Y255985D03*
Y245985D03*
Y235985D03*
Y225985D03*
X810065Y265985D03*
Y255985D03*
Y245985D03*
Y235985D03*
X800065Y265985D03*
Y255985D03*
Y245985D03*
Y235985D03*
X790065Y265985D03*
Y255985D03*
Y245985D03*
Y235985D03*
Y225985D03*
X857965Y273150D03*
X820065Y305985D03*
Y295985D03*
Y285985D03*
X810065Y295985D03*
Y285985D03*
X800065D03*
X790065D03*
Y295985D03*
X800065D03*
X810065Y305985D03*
X810000Y314000D03*
X810065Y325985D03*
X800065Y305985D03*
Y315985D03*
Y325985D03*
Y335985D03*
Y345985D03*
X790065Y305985D03*
Y315985D03*
Y325985D03*
X791500Y336000D03*
X790065Y345985D03*
X859407Y300314D03*
Y309914D03*
Y305114D03*
Y295314D03*
Y290314D03*
Y285314D03*
X790065Y415985D03*
Y405985D03*
Y395985D03*
Y375985D03*
X800065D03*
X790065Y365985D03*
X800065D03*
Y355985D03*
X790065D03*
X800065Y455985D03*
Y465985D03*
X790065D03*
Y455985D03*
Y445985D03*
Y435985D03*
X790191Y426486D03*
X809000Y429400D03*
X840057Y494320D03*
X835057D03*
X805771Y518743D03*
X789604Y519082D03*
X794604D03*
X836023Y508124D03*
X825161Y507954D03*
X820161D03*
X815161D03*
X805983Y508293D03*
X793015Y507785D03*
X790975Y621407D03*
X795975D03*
X800975D03*
X805975D03*
X810975D03*
X815975D03*
X820975D03*
X825975D03*
X830975D03*
X835975D03*
X840975D03*
X854971Y637313D03*
Y642313D03*
Y647313D03*
Y652313D03*
Y657313D03*
Y662313D03*
Y667313D03*
Y672313D03*
Y677313D03*
Y682313D03*
Y687313D03*
Y692313D03*
Y697313D03*
Y702313D03*
Y707313D03*
Y712313D03*
X916683Y62377D03*
Y57377D03*
Y52377D03*
Y47377D03*
Y42377D03*
Y37377D03*
Y32377D03*
Y27377D03*
Y22377D03*
Y17377D03*
X915546Y8514D03*
X910546D03*
X905546D03*
X900546D03*
X883222Y59214D03*
X888022D03*
X892822D03*
X897622D03*
X880922Y63714D03*
X885722D03*
X890522D03*
X895322D03*
X900122D03*
X916683Y132377D03*
Y127377D03*
Y122377D03*
Y117377D03*
Y112377D03*
Y107377D03*
Y102377D03*
Y97377D03*
Y92377D03*
Y87377D03*
Y82377D03*
Y77377D03*
Y72377D03*
Y67377D03*
X897250Y81510D03*
X902050D03*
Y86310D03*
X897250D03*
Y91110D03*
X902050D03*
X897250Y95910D03*
X902050D03*
X916683Y207377D03*
Y202377D03*
Y197377D03*
Y192377D03*
Y187377D03*
Y182377D03*
Y177377D03*
Y172377D03*
Y167377D03*
Y162377D03*
Y157377D03*
Y152377D03*
Y147377D03*
Y142377D03*
Y137377D03*
X900600Y201239D03*
X897803Y207684D03*
X902803D03*
X880222Y206781D03*
X875222D03*
X916683Y277377D03*
Y272377D03*
Y267377D03*
Y262377D03*
Y257377D03*
Y252377D03*
Y247377D03*
Y242377D03*
Y237377D03*
Y232377D03*
Y227377D03*
Y222377D03*
Y217377D03*
Y212377D03*
X897195Y275688D03*
X902195D03*
Y270688D03*
X897195D03*
X897803Y217684D03*
Y212684D03*
X902803Y217684D03*
Y212684D03*
X896031Y228468D03*
Y223468D03*
X891031D03*
Y228468D03*
Y238468D03*
X896031D03*
X891031Y233468D03*
X896031D03*
X868376Y271313D03*
X873376D03*
X880122Y216781D03*
X875122D03*
X880222Y211781D03*
X875222D03*
X916683Y347377D03*
Y342377D03*
Y337377D03*
Y332377D03*
Y327377D03*
Y322377D03*
Y317377D03*
Y312377D03*
Y307377D03*
Y302377D03*
Y297377D03*
Y292377D03*
Y287377D03*
Y282377D03*
X896030Y296330D03*
X901030D03*
X900995Y290712D03*
X895995D03*
X900819Y316367D03*
X895819D03*
X900716Y311058D03*
X895716D03*
X864207Y300314D03*
Y309914D03*
Y305114D03*
Y295314D03*
Y290314D03*
Y285314D03*
X916683Y422377D03*
Y417377D03*
Y412377D03*
Y407377D03*
Y402377D03*
Y397377D03*
Y392377D03*
Y387377D03*
Y382377D03*
Y377377D03*
Y372377D03*
Y367377D03*
Y362377D03*
Y357377D03*
Y352377D03*
X876451Y407949D03*
X880665Y410841D03*
X885665D03*
X890665D03*
X895665D03*
X900665D03*
X902091Y369397D03*
X897091D03*
X902091Y374397D03*
X897091D03*
Y379397D03*
X902091D03*
X888548Y392923D03*
X883548D03*
X893548D03*
X888548Y387923D03*
X893548D03*
X883548D03*
X916683Y492377D03*
Y487377D03*
Y482377D03*
Y477377D03*
Y472377D03*
Y467377D03*
Y462377D03*
Y457377D03*
Y452377D03*
Y447377D03*
Y442377D03*
Y437377D03*
Y432377D03*
Y427377D03*
Y562377D03*
Y557377D03*
Y552377D03*
Y547377D03*
Y542377D03*
Y537377D03*
Y532377D03*
Y527377D03*
Y522377D03*
Y517377D03*
Y512377D03*
Y507377D03*
Y502377D03*
Y497377D03*
Y637377D03*
Y632377D03*
Y627377D03*
Y622377D03*
Y617377D03*
Y612377D03*
Y607377D03*
Y602377D03*
Y597377D03*
Y592377D03*
Y587377D03*
Y582377D03*
Y577377D03*
Y572377D03*
Y567377D03*
Y707377D03*
Y702377D03*
Y697377D03*
Y692377D03*
Y687377D03*
Y682377D03*
Y677377D03*
Y672377D03*
Y667377D03*
Y662377D03*
Y657377D03*
Y652377D03*
Y647377D03*
Y642377D03*
X901041Y753684D03*
X903277Y749212D03*
X905513Y744740D03*
X907749Y740268D03*
X909985Y735796D03*
X912221Y731323D03*
X914457Y726851D03*
X916683Y722377D03*
Y717377D03*
Y712377D03*
G54D30*
X123800Y504600D03*
X148716Y570305D03*
X171979Y583387D03*
X203900Y634400D03*
X251200Y609800D03*
X284736Y598419D03*
X355889Y540188D03*
X365809Y509699D03*
X362180Y551390D03*
X667632Y486702D03*
Y490702D03*
Y494202D03*
Y482602D03*
G54D12*
X30900Y79600D03*
X81169Y734566D03*
X847271Y45720D03*
G54D21*
X31100Y512700D03*
X37500Y579400D03*
X126330Y445098D03*
X108492Y541948D03*
X102500Y499700D03*
X130400Y539900D03*
X126780Y562773D03*
X134800Y604800D03*
X137100Y589427D03*
X138970Y632277D03*
X117121Y579999D03*
X128700Y615500D03*
X138700Y636655D03*
X139400Y615000D03*
X113672Y605134D03*
X113512Y613401D03*
X113426Y609234D03*
X108137Y615870D03*
X113400Y621400D03*
X133835Y609620D03*
X134354Y632246D03*
X94818Y655471D03*
X118998Y701124D03*
X115598Y708228D03*
X133000Y656400D03*
X89560Y712200D03*
X109478Y713245D03*
X183900Y493100D03*
X147100Y483400D03*
X144943Y480031D03*
X178500Y492200D03*
X167999Y479200D03*
X149000Y494500D03*
X179100Y455800D03*
X207300Y471520D03*
X208400Y476900D03*
X207500Y483000D03*
X176252Y473571D03*
X176224Y468472D03*
X194411Y485447D03*
X193400Y463300D03*
X174036Y448700D03*
X151016Y445380D03*
X181938Y444600D03*
X190999Y446650D03*
X145000Y492200D03*
X187964Y493426D03*
X197847Y494417D03*
X167680Y510640D03*
X187699Y543279D03*
X187800Y547278D03*
X178200Y540400D03*
X209627Y540605D03*
X163300Y510400D03*
X174930Y534600D03*
X164784Y539407D03*
X167000Y535500D03*
X158200Y532900D03*
X183750Y524200D03*
X190936Y540928D03*
X176900Y496500D03*
X177600Y517400D03*
X198796Y505657D03*
X200402Y542169D03*
X203930Y540283D03*
X154400Y524400D03*
X190929Y512592D03*
X203356Y495487D03*
X199162Y602800D03*
X152640Y582742D03*
X197611Y630698D03*
X193400Y630600D03*
X184932Y601225D03*
X180571Y611325D03*
X177200Y633500D03*
X172449Y633644D03*
X156500Y598500D03*
X190944Y605862D03*
X199950Y617600D03*
X195500Y618000D03*
X200500Y622000D03*
X206800Y627047D03*
X207450Y622000D03*
X208423Y605303D03*
X165000Y614300D03*
X161047Y615989D03*
X160088Y608100D03*
X159500Y612300D03*
X153000Y594927D03*
X148210Y629830D03*
X148400Y607000D03*
X179344Y607509D03*
X155950Y592010D03*
X162500Y624850D03*
X173247Y607000D03*
X172848Y700108D03*
X150849Y710215D03*
X155846Y723282D03*
X240900Y440900D03*
X236400Y440800D03*
X280587Y491768D03*
X280700Y484600D03*
X239100Y450500D03*
X223146Y489341D03*
X267435Y442572D03*
X245800Y443600D03*
X215300Y512200D03*
X235002Y562120D03*
X224600Y560900D03*
X230277Y559321D03*
X214235Y539198D03*
X246400Y547900D03*
X246463Y553137D03*
X224900Y497730D03*
X260000Y517300D03*
X279654Y497255D03*
X279000Y555000D03*
X252500Y563200D03*
X229807Y530200D03*
X224000Y539130D03*
X225500Y557000D03*
X258300Y504750D03*
X256500Y552900D03*
X240274Y629709D03*
X213400Y621100D03*
X219466Y628146D03*
X251100Y595000D03*
X236400Y568800D03*
X265231Y570631D03*
X237500Y578550D03*
X236800Y574297D03*
X218300Y605000D03*
X221000Y601900D03*
X215900Y595500D03*
X232536Y588078D03*
X218298Y591749D03*
X226195Y603279D03*
X264750Y580250D03*
X247400Y576400D03*
X260096Y574693D03*
X249361Y693100D03*
X277600Y680200D03*
X218925Y666220D03*
X267584Y656531D03*
X250128Y678106D03*
X250900Y642100D03*
X331321Y198570D03*
X334200Y205400D03*
X335100Y237500D03*
X315866Y214556D03*
X328451Y207719D03*
X312800Y244461D03*
X321900Y249400D03*
X324600Y252600D03*
X330806Y392324D03*
X293326Y494174D03*
X339507Y433648D03*
X351597Y438869D03*
X354158Y430400D03*
X293800Y534000D03*
X292200Y548564D03*
X308253Y535182D03*
X288000Y561000D03*
X290590Y509859D03*
X336881Y530496D03*
X336953Y534506D03*
X331806Y561752D03*
X328012Y556569D03*
X318970Y565209D03*
X337600Y515500D03*
X339300Y526300D03*
X331240Y500920D03*
X331600Y512900D03*
X334900Y557600D03*
X316700Y631700D03*
X355200Y607700D03*
X345386Y604896D03*
X319401Y569678D03*
X347398Y599694D03*
X309765Y608200D03*
X348161Y592261D03*
X319831Y573790D03*
X315411Y701965D03*
X352600Y674489D03*
X290951Y673641D03*
X352557Y679888D03*
X317159Y667813D03*
X311798Y673233D03*
X325332Y685592D03*
X316550Y663250D03*
X327368Y651299D03*
X310100Y677950D03*
X297330Y682986D03*
X313000Y658500D03*
X291754Y680486D03*
X365000Y75500D03*
X387500Y458200D03*
X378200Y476600D03*
X383700Y500800D03*
X357379Y552518D03*
X357853Y500825D03*
X374049Y517383D03*
X357400Y559500D03*
X390769Y495379D03*
X384500Y616500D03*
X383313Y621780D03*
X375000Y573200D03*
X385700Y586100D03*
X366500Y586300D03*
X376676Y568400D03*
X395127Y568056D03*
X395100Y572899D03*
X364600Y670800D03*
X479040Y47134D03*
X488800Y62100D03*
X461350Y29800D03*
X443869Y43095D03*
X488974Y44580D03*
X483091Y33900D03*
X452490Y64240D03*
X457585Y70015D03*
X531050Y46998D03*
X544309Y39634D03*
X563620Y60160D03*
X530031Y32071D03*
X508855Y40905D03*
X534956Y62900D03*
X502400Y64400D03*
X588200Y44800D03*
X591347Y53907D03*
X603847Y60757D03*
X633137Y19759D03*
X579158Y73212D03*
X648910Y40090D03*
X669505Y41254D03*
X700689Y491390D03*
X704486Y488179D03*
X697100Y450200D03*
X681500Y501000D03*
X775100Y540000D03*
X754829Y502218D03*
X724242Y504713D03*
X764254Y544790D03*
X851008Y186924D03*
X853697Y161250D03*
X852922Y207800D03*
X834116Y330314D03*
X813916Y338614D03*
X846295Y383181D03*
X848820Y395572D03*
X839643Y390800D03*
X836284Y352842D03*
X835820Y380672D03*
X815600Y398300D03*
X825000Y428800D03*
X829700Y426800D03*
X798600Y502500D03*
X792300Y502200D03*
X864992Y175435D03*
X860486Y163694D03*
X870228Y217843D03*
X899400Y235700D03*
X898300Y284200D03*
X870447Y281493D03*
X870568Y302548D03*
X866800Y406100D03*
X887718Y375178D03*
X861420Y367269D03*
X861511Y352861D03*
X900379Y391262D03*
X860398Y394819D03*
G54D31*
X137824Y544746D03*
Y552346D03*
X135449Y558949D03*
Y566549D03*
X122600Y594800D03*
Y602400D03*
X149700Y723000D03*
Y715400D03*
X228201Y518368D03*
Y510768D03*
X249500Y616500D03*
Y624100D03*
X241800Y624000D03*
Y616400D03*
X311057Y193874D03*
Y201474D03*
X318763Y220690D03*
Y228290D03*
X311097Y220715D03*
Y228315D03*
X329435Y225684D03*
Y218084D03*
X477343Y33619D03*
Y41219D03*
X663847Y39907D03*
Y32307D03*
X655847Y39907D03*
Y32307D03*
X677447Y478527D03*
Y470927D03*
X699365Y510653D03*
Y518253D03*
X749875Y523096D03*
Y530696D03*
X779239Y522260D03*
Y529860D03*
X800291Y509468D03*
Y517068D03*
X885359Y223815D03*
Y216215D03*
X901690Y397644D03*
Y405244D03*
X894072Y397625D03*
Y405225D03*
X866541Y392586D03*
Y400186D03*
G54D22*
X54100Y586350D03*
X46500D03*
X100100Y705700D03*
X92500D03*
X325629Y183698D03*
X318029D03*
X325705Y191549D03*
X318105D03*
X328900Y235400D03*
X321300D03*
X685200Y490609D03*
X692800D03*
X888326Y201329D03*
X895926D03*
X885501Y209131D03*
X893101D03*
X869245Y212185D03*
X861645D03*
X881986Y275745D03*
X889586D03*
X881986Y299745D03*
X889586D03*
X881986Y307745D03*
X889586D03*
X881986Y291745D03*
X889586D03*
X881986Y283745D03*
X889586D03*
X885914Y398288D03*
X878314D03*
G54D40*
X96287Y572899D03*
X143823Y612046D03*
X250300Y630000D03*
X354662Y519446D03*
X308700Y511900D03*
X360980Y586886D03*
X586447Y57207D03*
X806825Y420615D03*
X815334Y390062D03*
G54D13*
X34652Y111485D03*
X33297Y703990D03*
X148206Y21054D03*
X261147Y405580D03*
X486498Y356293D03*
X807831Y734367D03*
X899219Y47960D03*
G54D23*
X41868Y567316D03*
X49250Y580250D03*
X96900Y712200D03*
X189771Y559210D03*
X197030Y583440D03*
X870990Y222573D03*
G54D41*
X133600Y614300D03*
X204800Y487100D03*
X166761Y492320D03*
X212165Y483008D03*
X191694Y532628D03*
X170800Y503100D03*
X211378Y532401D03*
X166737Y502154D03*
X179000Y503100D03*
X207278Y532401D03*
X162537Y502154D03*
X200031Y532794D03*
X147247Y501787D03*
X151351Y501797D03*
X158294Y502154D03*
X192471Y610938D03*
X188431Y609938D03*
X147723Y612196D03*
X217908Y479635D03*
X222100Y475200D03*
X233300Y543700D03*
X237300D03*
X246980Y558568D03*
X219473Y532173D03*
X221800Y608300D03*
X225900Y608200D03*
X273895Y567952D03*
X272900Y584300D03*
X242600Y575100D03*
X269806Y567952D03*
X330600Y505900D03*
X288286Y583855D03*
X351500Y584090D03*
X314800Y678000D03*
X357000Y586800D03*
X373400Y622600D03*
X498150Y55330D03*
X459610Y33640D03*
X493500Y63900D03*
X511500Y54800D03*
X837816Y344414D03*
X848820Y400072D03*
G54D14*
X70865Y98425D03*
Y472441D03*
X49212Y740157D03*
X314960Y472441D03*
X364173Y740157D03*
X405511Y39370D03*
X587795Y307087D03*
X590551Y472441D03*
X612204Y606299D03*
X875984Y31496D03*
Y472441D03*
Y606299D03*
Y740157D03*
G54D32*
X78525Y554363D03*
X78524Y558398D03*
X98044Y555240D03*
X98076Y560166D03*
X139800Y620200D03*
X126200Y626300D03*
X184800Y489000D03*
X199400Y483000D03*
X168101Y469168D03*
Y473268D03*
X171500Y526700D03*
X198846Y501509D03*
X200600Y608800D03*
X172402Y574058D03*
X198755Y625814D03*
X159700Y619900D03*
X149557Y602562D03*
X145800Y596700D03*
X204000Y638200D03*
X176034Y619120D03*
X147600Y620200D03*
X211700Y642200D03*
X241400Y543700D03*
X226357Y534556D03*
X238000Y556100D03*
Y551900D03*
X229700Y505300D03*
X255861Y548308D03*
X247600Y536200D03*
X255200Y535800D03*
X235500Y593500D03*
X228192Y622802D03*
X223000Y597200D03*
Y593200D03*
X224000Y571900D03*
X224375Y576816D03*
X224300Y585900D03*
X228000Y567000D03*
X265300Y584500D03*
X263288Y666467D03*
X222092Y642006D03*
X328100Y387774D03*
X342200Y377800D03*
X320725Y558073D03*
X324585Y566198D03*
X344200Y579231D03*
X324756Y571267D03*
X305817Y682959D03*
X362280Y544200D03*
X375915Y617425D03*
X357435Y661505D03*
X493818Y42607D03*
X490250Y33781D03*
X507300Y65000D03*
X535006Y68742D03*
X700891Y484208D03*
X693400Y455000D03*
X698300Y442100D03*
X825100Y422612D03*
X811481Y403117D03*
G54D50*
X260513Y564135D03*
G54D15*
X65400Y546000D03*
X100619Y564385D03*
X97113Y564386D03*
X92870Y564415D03*
X78247Y562479D03*
X137100Y597000D03*
X133600D03*
X207600Y495580D03*
X327538Y600224D03*
X689875Y468836D03*
X686496Y512847D03*
X690134Y512896D03*
X693692Y512862D03*
X765453Y525125D03*
X786667Y511552D03*
X782667D03*
X760375Y525096D03*
X756375D03*
X769453Y525125D03*
X773453D03*
X790667Y511552D03*
X794667D03*
G54D60*
X370950Y563500D03*
X363450Y559625D03*
Y567375D03*
X828266Y350214D03*
X820766Y346339D03*
Y354089D03*
G54D33*
X81925Y554363D03*
X81924Y558398D03*
X101444Y555240D03*
X101476Y560166D03*
X129600Y626300D03*
X188200Y489000D03*
X202800Y483000D03*
X171501Y469168D03*
Y473268D03*
X174900Y526700D03*
X202246Y501509D03*
X204000Y608800D03*
X175802Y574058D03*
X202155Y625814D03*
X163100Y619900D03*
X152957Y602562D03*
X149200Y596700D03*
X207400Y638200D03*
X179434Y619120D03*
X143200Y620200D03*
X151000D03*
X244800Y543700D03*
X229757Y534556D03*
X241400Y556100D03*
Y551900D03*
X233100Y505300D03*
X259261Y548308D03*
X251000Y536200D03*
X258600Y535800D03*
X238900Y593500D03*
X231592Y622802D03*
X226400Y597200D03*
Y593200D03*
X227400Y571900D03*
X227775Y576816D03*
X227700Y585900D03*
X231400Y567000D03*
X268700Y584500D03*
X266688Y666467D03*
X215100Y642200D03*
X225492Y642006D03*
X331500Y387774D03*
X345600Y377800D03*
X324125Y558073D03*
X327985Y566198D03*
X347600Y579231D03*
X328156Y571267D03*
X309217Y682959D03*
X365680Y544200D03*
X379315Y617425D03*
X360835Y661505D03*
X497218Y42607D03*
X493650Y33781D03*
X510700Y65000D03*
X538406Y68742D03*
X704291Y484208D03*
X696800Y455000D03*
X701700Y442100D03*
X828500Y422612D03*
X814881Y403117D03*
G54D51*
X346457Y57007D03*
X353543Y62913D03*
Y55039D03*
X346457Y66850D03*
Y74724D03*
Y84567D03*
X353543Y86535D03*
Y78661D03*
Y70787D03*
G54D24*
X47468Y567316D03*
X54850Y580250D03*
X102500Y712200D03*
X195371Y559210D03*
X202630Y583440D03*
X876590Y222573D03*
G54D42*
X133600Y617700D03*
X204800Y490500D03*
X212165Y486408D03*
X191694Y536028D03*
X170800Y506500D03*
X166761Y495720D03*
X211378Y535801D03*
X166737Y505554D03*
X179000Y506500D03*
X207278Y535801D03*
X162537Y505554D03*
X200031Y536194D03*
X147247Y505187D03*
X151351Y505197D03*
X158294Y505554D03*
X192471Y614338D03*
X188431Y613338D03*
X147723Y615596D03*
X217908Y483035D03*
X222100Y478600D03*
X233300Y547100D03*
X237300D03*
X246980Y561968D03*
X219473Y535573D03*
X221800Y611700D03*
X225900Y611600D03*
X273895Y571352D03*
X272900Y587700D03*
X242600Y578500D03*
X269806Y571352D03*
X330600Y509300D03*
X288286Y587255D03*
X351500Y587490D03*
X314800Y681400D03*
X357000Y590200D03*
X373400Y626000D03*
X498150Y58730D03*
X459610Y37040D03*
X493500Y67300D03*
X511500Y58200D03*
X837816Y347814D03*
X848820Y403472D03*
G54D25*
X64350Y582500D03*
X129100Y602100D03*
X141189Y601337D03*
X148840Y555135D03*
X153495Y555166D03*
X213000Y522800D03*
X245100Y635800D03*
X354000Y637700D03*
X349200D03*
X377714Y627580D03*
X375600Y604200D03*
G54D16*
X65400Y549600D03*
X78247Y566079D03*
X137100Y600600D03*
X133600D03*
X100619Y567985D03*
X97113Y567986D03*
X92870Y568015D03*
X207600Y499180D03*
X327538Y603824D03*
X689875Y472436D03*
X686496Y516447D03*
X690134Y516496D03*
X693692Y516462D03*
X765453Y528725D03*
X786667Y515152D03*
X782667D03*
X760375Y528696D03*
X756375D03*
X769453Y528725D03*
X773453D03*
X790667Y515152D03*
X794667D03*
G54D61*
X367620Y603164D03*
Y599564D03*
X361800Y603500D03*
Y599900D03*
G54D34*
X140550Y503660D03*
Y501100D03*
Y498540D03*
X134050D03*
Y503660D03*
X322850Y515460D03*
Y512900D03*
Y510340D03*
X316350D03*
Y515460D03*
X337502Y594713D03*
Y592153D03*
Y589593D03*
X331002D03*
Y594713D03*
X303250Y600760D03*
Y598200D03*
Y595640D03*
X296750D03*
Y600760D03*
X365230Y534960D03*
Y532400D03*
Y529840D03*
X358730D03*
Y534960D03*
X368250Y522660D03*
Y520100D03*
Y517540D03*
X361750D03*
Y522660D03*
G54D43*
X184800Y484556D03*
X171780Y496031D03*
X197400Y549000D03*
X170597Y539852D03*
X175200Y555000D03*
X184700Y552000D03*
X160157Y537164D03*
X149824Y542794D03*
X202380Y567970D03*
X169021Y610228D03*
X157800Y602900D03*
X154903Y608458D03*
X169242Y603107D03*
X163991Y606162D03*
X207820Y570860D03*
X206900Y577100D03*
X179500Y602800D03*
X186800Y595600D03*
X197264Y596849D03*
X224300Y552500D03*
X220500Y557800D03*
X221700Y545500D03*
X219700Y563100D03*
X236074Y536841D03*
X236260Y529177D03*
X257600Y543400D03*
X213201Y570843D03*
X219375Y581711D03*
X219638Y576359D03*
X219688Y587096D03*
X223292Y567000D03*
X219000Y617500D03*
X378965Y610613D03*
X361792Y625652D03*
G54D70*
X801024Y24409D03*
X811024D03*
X821024D03*
G54D52*
X339331Y49803D03*
X360669Y91929D03*
G54D71*
X850667Y383181D03*
G54D53*
X339331Y91929D03*
X360669Y49803D03*
G54D44*
X199890Y468960D03*
Y471520D03*
Y474080D03*
Y476640D03*
X183710D03*
Y474080D03*
Y471520D03*
Y468960D03*
X310092Y575349D03*
Y577909D03*
Y580469D03*
Y583029D03*
X297292D03*
Y580469D03*
Y577909D03*
Y575349D03*
X323039Y677049D03*
Y674489D03*
Y671929D03*
Y669369D03*
Y666809D03*
Y664249D03*
Y661689D03*
X345239D03*
Y664249D03*
Y666809D03*
Y669369D03*
Y671929D03*
Y674489D03*
Y677049D03*
G54D35*
X105474Y535824D03*
X91800Y677300D03*
X181148Y568251D03*
X192089Y582625D03*
X291811Y553256D03*
X866286Y159490D03*
X878598Y391533D03*
G54D17*
X64151Y517477D03*
X64251Y509877D03*
X120273Y500759D03*
X86659Y517477D03*
X86673Y510000D03*
X81032Y517477D03*
X81068Y509866D03*
X92286Y517477D03*
X92273Y510000D03*
X97913Y517477D03*
X97900Y510000D03*
X69778Y517477D03*
X69878Y509777D03*
X75405Y517477D03*
X75373Y509879D03*
X121643Y618027D03*
X148000Y475500D03*
X143700D03*
X152589Y489481D03*
X192300Y493500D03*
X212118Y470993D03*
X167000Y520500D03*
X146700Y530100D03*
X156501Y564267D03*
X162700Y495700D03*
X158600Y528400D03*
X167454Y530877D03*
X163300Y530600D03*
X174900Y506500D03*
X200910Y563190D03*
X179400Y531800D03*
X183670Y531766D03*
X196013Y536175D03*
X146600Y520700D03*
X196890Y567300D03*
X184400Y611300D03*
X212500Y611900D03*
X155341Y616572D03*
X196500Y611300D03*
X194718Y625994D03*
X184700Y591000D03*
X218500Y490700D03*
X273809Y563811D03*
X215448Y535601D03*
X269709Y563813D03*
X224000Y622700D03*
X238100Y586400D03*
X252300Y580700D03*
X242100Y586400D03*
X296680Y556264D03*
X288286Y579720D03*
X309765Y603700D03*
X344102Y594663D03*
X312000Y666700D03*
X307849Y668900D03*
X358120Y547604D03*
X357500Y566900D03*
X369800Y578000D03*
X380000Y601800D03*
X357655Y681145D03*
X521330Y85580D03*
X815016Y348514D03*
X819100Y393600D03*
G54D62*
X369480Y622436D03*
Y626036D03*
G54D26*
X64350Y576900D03*
X129100Y596500D03*
X141189Y595737D03*
X148840Y549535D03*
X153495Y549566D03*
X213000Y517200D03*
X245100Y630200D03*
X354000Y632100D03*
X349200D03*
X377714Y621980D03*
X375600Y598600D03*
G54D27*
X89764Y238386D03*
X309252Y413583D03*
G54D36*
X99874Y535824D03*
X86200Y677300D03*
X175548Y568251D03*
X186489Y582625D03*
X286211Y553256D03*
X860686Y159490D03*
X872998Y391533D03*
G54D18*
X64151Y514077D03*
X64251Y506477D03*
X120273Y497359D03*
X86659Y514077D03*
X86673Y506600D03*
X81032Y514077D03*
X81068Y506466D03*
X92286Y514077D03*
X92273Y506600D03*
X97913Y514077D03*
X97900Y506600D03*
X69778Y514077D03*
X69878Y506377D03*
X75405Y514077D03*
X75373Y506479D03*
X121643Y614627D03*
X162700Y492300D03*
X148000Y472100D03*
X143700D03*
X152589Y486081D03*
X192300Y490100D03*
X212118Y467593D03*
X167000Y517100D03*
X146700Y526700D03*
X156501Y560867D03*
X196890Y563900D03*
X158600Y525000D03*
X167454Y527477D03*
X163300Y527200D03*
X174900Y503100D03*
X200910Y559790D03*
X179400Y528400D03*
X183670Y528366D03*
X196013Y532775D03*
X146600Y517300D03*
X184400Y607900D03*
X212500Y608500D03*
X155341Y613172D03*
X196500Y607900D03*
X194718Y622594D03*
X184700Y587600D03*
X218500Y487300D03*
X273809Y560411D03*
X215448Y532201D03*
X269709Y560413D03*
X224000Y619300D03*
X238100Y583000D03*
X252300Y577300D03*
X242100Y583000D03*
X296680Y552864D03*
X288286Y576320D03*
X309765Y600300D03*
X344102Y591263D03*
X312000Y663300D03*
X307849Y665500D03*
X357500Y563500D03*
X358120Y544204D03*
X369800Y574600D03*
X380000Y598400D03*
X357655Y677745D03*
X521330Y82180D03*
X815016Y345114D03*
X819100Y390200D03*
G54D72*
X853167Y383181D03*
G54D63*
X488838Y137225D03*
G54D54*
X305906Y182874D03*
G54D45*
X178600Y483800D03*
X201801Y684252D03*
X225601D03*
G54D73*
G01X-9023Y-84471D02*
X-8149Y-83596D01*
X-7494Y-82138D01*
X-7057Y-80095D01*
X-7494Y-78346D01*
X-8367Y-77179D01*
X-9896Y-76304D01*
X-15791D01*
Y-93804D01*
X-8586D01*
X-7057Y-92638D01*
X-6184Y-90887D01*
X-5747Y-88846D01*
X-6184Y-86804D01*
X-7494Y-85054D01*
X-9023Y-84471D01*
X-15791D01*
G01X3674Y-93804D02*
Y-82138D01*
G01Y-84471D02*
X4766Y-83304D01*
X5858Y-82429D01*
X7386Y-82138D01*
X8477Y-82429D01*
X9788Y-83304D01*
G01X19646Y-99054D02*
X20956Y-99637D01*
X22703Y-99054D01*
X23794Y-97888D01*
X24668Y-96429D01*
X25977Y-91763D01*
X28816Y-82138D01*
G01X21829D02*
X25977Y-91763D01*
G01X45224Y-83596D02*
X43696Y-82429D01*
X42386Y-82138D01*
X40639Y-82721D01*
X39329Y-83887D01*
X38456Y-85929D01*
X38237Y-87971D01*
X38456Y-90013D01*
X39329Y-91763D01*
X40639Y-93221D01*
X42386Y-93804D01*
X43914Y-93221D01*
X45224Y-92054D01*
G01X55956Y-85929D02*
X62943D01*
X62288Y-83887D01*
X61196Y-82721D01*
X59668Y-82138D01*
X58139Y-82429D01*
X56829Y-83304D01*
X55956Y-85346D01*
X55519Y-87096D01*
Y-88846D01*
X55956Y-90596D01*
X57048Y-92346D01*
X58358Y-93512D01*
X59886Y-93804D01*
X61414Y-93221D01*
X62943Y-91471D01*
G01X99034Y-77763D02*
X97724Y-76887D01*
X96196Y-76304D01*
X94449D01*
X92484Y-77179D01*
X90956Y-78637D01*
X89864Y-80388D01*
X88991Y-83304D01*
X88772Y-85929D01*
X89209Y-88554D01*
X89864Y-90304D01*
X91174Y-92054D01*
X92703Y-93221D01*
X94231Y-93804D01*
X95759D01*
X97288Y-93221D01*
X98598Y-92346D01*
X99690Y-91180D01*
G01X115661Y-93804D02*
Y-82138D01*
G01Y-84179D02*
X114788Y-83013D01*
X113477Y-82429D01*
X111949Y-82138D01*
X110421Y-82721D01*
X109111Y-83887D01*
X108237Y-85637D01*
X107801Y-87971D01*
X108237Y-90304D01*
X109111Y-92054D01*
X110421Y-93221D01*
X111949Y-93804D01*
X113477Y-93512D01*
X114788Y-92638D01*
X115661Y-91471D01*
G01X125519Y-93804D02*
Y-82138D01*
G01Y-85054D02*
X126393Y-83596D01*
X127703Y-82429D01*
X129449Y-82138D01*
X130977Y-82429D01*
X132288Y-83596D01*
X132943Y-85637D01*
Y-93804D01*
G01X142146Y-99054D02*
X143456Y-99637D01*
X145203Y-99054D01*
X146294Y-97888D01*
X147168Y-96429D01*
X148477Y-91763D01*
X151316Y-82138D01*
G01X144329D02*
X148477Y-91763D01*
G01X164231Y-93804D02*
X162921Y-93512D01*
X161611Y-92346D01*
X160737Y-90304D01*
X160301Y-87971D01*
X160737Y-85637D01*
X161611Y-83596D01*
X162921Y-82429D01*
X164231Y-82138D01*
X165541Y-82429D01*
X166851Y-83596D01*
X167724Y-85637D01*
X167943Y-87971D01*
X167724Y-90304D01*
X166851Y-92346D01*
X165541Y-93512D01*
X164231Y-93804D01*
G01X178019D02*
Y-82138D01*
G01Y-85054D02*
X178893Y-83596D01*
X180203Y-82429D01*
X181949Y-82138D01*
X183477Y-82429D01*
X184788Y-83596D01*
X185443Y-85637D01*
Y-93804D01*
G01X214111Y-76304D02*
X219351D01*
G01X216731D02*
Y-93804D01*
G01X214111D02*
X219351D01*
G01X234231D02*
X232484Y-93512D01*
X230956Y-92346D01*
X229646Y-90596D01*
X228772Y-88554D01*
X228336Y-86221D01*
Y-83887D01*
X228772Y-81554D01*
X229646Y-79512D01*
X230956Y-77763D01*
X232484Y-76596D01*
X234231Y-76304D01*
X235977Y-76596D01*
X237506Y-77763D01*
X238816Y-79512D01*
X239690Y-81554D01*
X240126Y-83887D01*
Y-86221D01*
X239690Y-88554D01*
X238816Y-90596D01*
X237506Y-92346D01*
X235977Y-93512D01*
X234231Y-93804D01*
G01X246054D02*
Y-76304D01*
X251731Y-90887D01*
X257408Y-76304D01*
Y-93804D01*
G01X285639Y-99637D02*
X283456Y-96721D01*
X282364Y-93804D01*
Y-82138D01*
X283456Y-79221D01*
X285639Y-76304D01*
G01X298554Y-93804D02*
Y-76304D01*
X304231Y-90887D01*
X309908Y-76304D01*
Y-93804D01*
G01X321731Y-94387D02*
X321294Y-94096D01*
Y-93512D01*
X321731Y-93221D01*
X322168Y-93512D01*
Y-94096D01*
X321731Y-94387D01*
G01X335083Y-79221D02*
X336393Y-77471D01*
X337921Y-76596D01*
X339668Y-76304D01*
X341851Y-76887D01*
X343379Y-78346D01*
X343816Y-80095D01*
X343598Y-81846D01*
X342724Y-83304D01*
X338358Y-86221D01*
X336393Y-88262D01*
X335083Y-91180D01*
X334646Y-93804D01*
X343816D01*
G01X374231D02*
X372921Y-93512D01*
X371611Y-92346D01*
X370737Y-90304D01*
X370301Y-87971D01*
X370737Y-85637D01*
X371611Y-83596D01*
X372921Y-82429D01*
X374231Y-82138D01*
X375541Y-82429D01*
X376851Y-83596D01*
X377724Y-85637D01*
X377943Y-87971D01*
X377724Y-90304D01*
X376851Y-92346D01*
X375541Y-93512D01*
X374231Y-93804D01*
G01X388019D02*
Y-82138D01*
G01Y-85054D02*
X388893Y-83596D01*
X390203Y-82429D01*
X391949Y-82138D01*
X393477Y-82429D01*
X394788Y-83596D01*
X395443Y-85637D01*
Y-93804D01*
G01X409231D02*
Y-76304D01*
G01X422146Y-99054D02*
X423456Y-99637D01*
X425203Y-99054D01*
X426294Y-97888D01*
X427168Y-96429D01*
X428477Y-91763D01*
X431316Y-82138D01*
G01X424329D02*
X428477Y-91763D01*
G01X445323Y-99637D02*
X447506Y-96721D01*
X448598Y-93804D01*
Y-82138D01*
X447506Y-79221D01*
X445323Y-76304D01*
G01X176054Y-48804D02*
Y-31304D01*
X181731Y-45887D01*
X187408Y-31304D01*
Y-48804D01*
G01X199231D02*
X197921Y-48512D01*
X196611Y-47346D01*
X195737Y-45304D01*
X195301Y-42971D01*
X195737Y-40637D01*
X196611Y-38596D01*
X197921Y-37429D01*
X199231Y-37138D01*
X200541Y-37429D01*
X201851Y-38596D01*
X202724Y-40637D01*
X202943Y-42971D01*
X202724Y-45304D01*
X201851Y-47346D01*
X200541Y-48512D01*
X199231Y-48804D01*
G01X220661Y-31304D02*
Y-48804D01*
G01Y-46180D02*
X219788Y-47638D01*
X218477Y-48512D01*
X216949Y-48804D01*
X215203Y-48221D01*
X213893Y-46763D01*
X213019Y-45013D01*
X212801Y-42971D01*
X213019Y-40929D01*
X213893Y-39179D01*
X215203Y-37721D01*
X216949Y-37138D01*
X218477Y-37429D01*
X219569Y-38013D01*
X220661Y-39179D01*
G01X230956Y-40929D02*
X237943D01*
X237288Y-38887D01*
X236196Y-37721D01*
X234668Y-37138D01*
X233139Y-37429D01*
X231829Y-38304D01*
X230956Y-40346D01*
X230519Y-42096D01*
Y-43846D01*
X230956Y-45596D01*
X232048Y-47346D01*
X233358Y-48512D01*
X234886Y-48804D01*
X236414Y-48221D01*
X237943Y-46471D01*
G01X251731Y-48804D02*
Y-31304D01*
G01X504231Y-93804D02*
Y-76304D01*
X501611Y-79804D01*
G01Y-93804D02*
X506851D01*
G01X517583Y-86513D02*
X519111Y-84471D01*
X520421Y-83304D01*
X522168Y-82721D01*
X523696Y-83304D01*
X524788Y-84471D01*
X525661Y-86221D01*
X525879Y-88262D01*
X525661Y-90013D01*
X524788Y-91763D01*
X523477Y-93221D01*
X521949Y-93804D01*
X520203Y-93221D01*
X518674Y-91471D01*
X517801Y-88846D01*
X517583Y-85929D01*
X518019Y-82138D01*
X518674Y-80095D01*
X519766Y-78054D01*
X521294Y-76596D01*
X522823Y-76304D01*
X524351Y-76887D01*
X525443Y-78346D01*
G01X534428Y-90304D02*
X535737Y-92346D01*
X537484Y-93512D01*
X539449Y-93804D01*
X541196Y-93512D01*
X542943Y-92054D01*
X544034Y-90304D01*
X544253Y-88554D01*
X543816Y-86513D01*
X542288Y-85054D01*
X540759Y-84471D01*
X538794D01*
G01X540759D02*
X542069Y-83596D01*
X543161Y-82138D01*
X543598Y-80388D01*
X543161Y-78637D01*
X542069Y-77179D01*
X540104Y-76304D01*
X538139Y-76596D01*
X536174Y-77763D01*
G01X559351Y-93804D02*
Y-76304D01*
X551272Y-88846D01*
X562190D01*
G01X570083Y-79221D02*
X571393Y-77471D01*
X572921Y-76596D01*
X574668Y-76304D01*
X576851Y-76887D01*
X578379Y-78346D01*
X578816Y-80095D01*
X578598Y-81846D01*
X577724Y-83304D01*
X573358Y-86221D01*
X571393Y-88262D01*
X570083Y-91180D01*
X569646Y-93804D01*
X578816D01*
G01X491114Y-48804D02*
Y-31304D01*
X496354D01*
X498101Y-32179D01*
X499411Y-34221D01*
X499848Y-36554D01*
X499411Y-38887D01*
X498319Y-40637D01*
X496354Y-41513D01*
X491114D01*
G01X517784Y-32763D02*
X516474Y-31887D01*
X514946Y-31304D01*
X513199D01*
X511234Y-32179D01*
X509706Y-33637D01*
X508614Y-35388D01*
X507741Y-38304D01*
X507522Y-40929D01*
X507959Y-43554D01*
X508614Y-45304D01*
X509924Y-47054D01*
X511453Y-48221D01*
X512981Y-48804D01*
X514509D01*
X516038Y-48221D01*
X517348Y-47346D01*
X518440Y-46180D01*
G01X532227Y-39471D02*
X533101Y-38596D01*
X533756Y-37138D01*
X534193Y-35095D01*
X533756Y-33346D01*
X532883Y-32179D01*
X531354Y-31304D01*
X525459D01*
Y-48804D01*
X532664D01*
X534193Y-47638D01*
X535066Y-45887D01*
X535503Y-43846D01*
X535066Y-41804D01*
X533756Y-40054D01*
X532227Y-39471D01*
X525459D01*
G01X541431Y-54637D02*
X554531D01*
G01X560459Y-48804D02*
Y-31304D01*
X570503Y-48804D01*
Y-31304D01*
G01X582981Y-48804D02*
X581234Y-48512D01*
X579706Y-47346D01*
X578396Y-45596D01*
X577522Y-43554D01*
X577086Y-41221D01*
Y-38887D01*
X577522Y-36554D01*
X578396Y-34512D01*
X579706Y-32763D01*
X581234Y-31596D01*
X582981Y-31304D01*
X584727Y-31596D01*
X586256Y-32763D01*
X587566Y-34512D01*
X588440Y-36554D01*
X588876Y-38887D01*
Y-41221D01*
X588440Y-43554D01*
X587566Y-45596D01*
X586256Y-47346D01*
X584727Y-48512D01*
X582981Y-48804D01*
G01X633822Y-31304D02*
X639281Y-48804D01*
X644740Y-31304D01*
G01X661148Y-48804D02*
X652414D01*
Y-31304D01*
X661148D01*
G01X657654Y-39762D02*
X652414D01*
G01X669914Y-48804D02*
Y-31304D01*
X675373D01*
X677119Y-32179D01*
X678211Y-33346D01*
X678648Y-35679D01*
X678211Y-38013D01*
X676901Y-39471D01*
X675373Y-40346D01*
X669914D01*
G01X675373D02*
X678648Y-48804D01*
G01X691781Y-49387D02*
X691344Y-49096D01*
Y-48512D01*
X691781Y-48221D01*
X692218Y-48512D01*
Y-49096D01*
X691781Y-49387D01*
G01X661383Y-79221D02*
X662693Y-77471D01*
X664221Y-76596D01*
X665968Y-76304D01*
X668151Y-76887D01*
X669679Y-78346D01*
X670116Y-80095D01*
X669898Y-81846D01*
X669024Y-83304D01*
X664658Y-86221D01*
X662693Y-88262D01*
X661383Y-91180D01*
X660946Y-93804D01*
X670116D01*
G01X839985Y-84471D02*
X839111Y-83596D01*
X838456Y-82138D01*
X838019Y-80095D01*
X838456Y-78346D01*
X839329Y-77179D01*
X840858Y-76304D01*
X846753D01*
Y-93804D01*
X839548D01*
X838019Y-92638D01*
X837146Y-90887D01*
X836709Y-88846D01*
X837146Y-86804D01*
X838456Y-85054D01*
X839985Y-84471D01*
X846753D01*
G01X829908Y-93804D02*
Y-76304D01*
X824231Y-90887D01*
X818554Y-76304D01*
Y-93804D01*
G01X812190D02*
X806731Y-76304D01*
X801272Y-93804D01*
G01X803238Y-87679D02*
X810225D01*
G01X793816Y-91471D02*
X792069Y-92929D01*
X790104Y-93804D01*
X788358D01*
X786611Y-92929D01*
X785301Y-91471D01*
X784646Y-89429D01*
X785083Y-87388D01*
X786174Y-85637D01*
X788139Y-84471D01*
X790759Y-83887D01*
X792288Y-82721D01*
X792943Y-80679D01*
X792506Y-78637D01*
X791414Y-77179D01*
X789886Y-76304D01*
X788358D01*
X786829Y-76887D01*
X785519Y-78346D01*
G01X776534Y-93804D02*
Y-76304D01*
G01X768238D02*
X776534Y-87096D01*
G01X766928Y-93804D02*
X772823Y-82138D01*
G01X767364Y-31304D02*
Y-48804D01*
X776098D01*
G01X793161D02*
Y-37138D01*
G01Y-39179D02*
X792288Y-38013D01*
X790977Y-37429D01*
X789449Y-37138D01*
X787921Y-37721D01*
X786611Y-38887D01*
X785737Y-40637D01*
X785301Y-42971D01*
X785737Y-45304D01*
X786611Y-47054D01*
X787921Y-48221D01*
X789449Y-48804D01*
X790977Y-48512D01*
X792288Y-47638D01*
X793161Y-46471D01*
G01X802146Y-54054D02*
X803456Y-54637D01*
X805203Y-54054D01*
X806294Y-52888D01*
X807168Y-51429D01*
X808477Y-46763D01*
X811316Y-37138D01*
G01X804329D02*
X808477Y-46763D01*
G01X820956Y-40929D02*
X827943D01*
X827288Y-38887D01*
X826196Y-37721D01*
X824668Y-37138D01*
X823139Y-37429D01*
X821829Y-38304D01*
X820956Y-40346D01*
X820519Y-42096D01*
Y-43846D01*
X820956Y-45596D01*
X822048Y-47346D01*
X823358Y-48512D01*
X824886Y-48804D01*
X826414Y-48221D01*
X827943Y-46471D01*
G01X838674Y-48804D02*
Y-37138D01*
G01Y-39471D02*
X839766Y-38304D01*
X840858Y-37429D01*
X842386Y-37138D01*
X843477Y-37429D01*
X844788Y-38304D01*
G01X931781Y-93804D02*
X930034Y-93512D01*
X928506Y-92346D01*
X927196Y-90596D01*
X926322Y-88554D01*
X925886Y-86221D01*
Y-83887D01*
X926322Y-81554D01*
X927196Y-79512D01*
X928506Y-77763D01*
X930034Y-76596D01*
X931781Y-76304D01*
X933527Y-76596D01*
X935056Y-77763D01*
X936366Y-79512D01*
X937240Y-81554D01*
X937676Y-83887D01*
Y-86221D01*
X937240Y-88554D01*
X936366Y-90596D01*
X935056Y-92346D01*
X933527Y-93512D01*
X931781Y-93804D01*
G01X933527Y-89137D02*
X936148Y-93804D01*
G01X944478Y-76304D02*
Y-88846D01*
X945351Y-91471D01*
X947098Y-93221D01*
X949281Y-93804D01*
X951464Y-93221D01*
X953211Y-91471D01*
X954084Y-88846D01*
Y-76304D01*
G01X964161D02*
X969401D01*
G01X966781D02*
Y-93804D01*
G01X964161D02*
X969401D01*
G01X979259D02*
Y-76304D01*
X989303Y-93804D01*
Y-76304D01*
G01X1006584Y-77763D02*
X1005274Y-76887D01*
X1003746Y-76304D01*
X1001999D01*
X1000034Y-77179D01*
X998506Y-78637D01*
X997414Y-80388D01*
X996541Y-83304D01*
X996322Y-85929D01*
X996759Y-88554D01*
X997414Y-90304D01*
X998724Y-92054D01*
X1000253Y-93221D01*
X1001781Y-93804D01*
X1003309D01*
X1004838Y-93221D01*
X1006148Y-92346D01*
X1007240Y-91180D01*
G01X1019281Y-93804D02*
Y-85929D01*
X1014914Y-76304D01*
G01X1023648D02*
X1019281Y-85929D01*
G01X909478Y-48804D02*
Y-31304D01*
X913844D01*
X915591Y-32179D01*
X916901Y-33346D01*
X917993Y-35095D01*
X918866Y-37138D01*
X919084Y-40054D01*
X918866Y-42971D01*
X917993Y-45013D01*
X916901Y-46763D01*
X915591Y-47929D01*
X913844Y-48804D01*
X909478D01*
G01X928506Y-40929D02*
X935493D01*
X934838Y-38887D01*
X933746Y-37721D01*
X932218Y-37138D01*
X930689Y-37429D01*
X929379Y-38304D01*
X928506Y-40346D01*
X928069Y-42096D01*
Y-43846D01*
X928506Y-45596D01*
X929598Y-47346D01*
X930908Y-48512D01*
X932436Y-48804D01*
X933964Y-48221D01*
X935493Y-46471D01*
G01X946006Y-46763D02*
X947098Y-47929D01*
X948626Y-48804D01*
X949936D01*
X951246Y-48221D01*
X952119Y-47346D01*
X952556Y-46180D01*
X952338Y-44429D01*
X951464Y-43554D01*
X947534Y-41804D01*
X946661Y-39762D01*
X947098Y-38304D01*
X947971Y-37429D01*
X949281Y-37138D01*
X950591Y-37429D01*
X951901Y-38304D01*
G01X966781Y-37138D02*
Y-48804D01*
G01Y-32471D02*
X966344Y-32179D01*
Y-31596D01*
X966781Y-31304D01*
X967218Y-31596D01*
Y-32179D01*
X966781Y-32471D01*
G01X981224Y-53179D02*
X982753Y-54346D01*
X984499Y-54637D01*
X986027Y-54346D01*
X987338Y-52888D01*
X988211Y-50846D01*
Y-37138D01*
G01Y-39471D02*
X987338Y-38304D01*
X986027Y-37429D01*
X984499Y-37138D01*
X982753Y-37721D01*
X981661Y-38887D01*
X980787Y-40929D01*
X980351Y-42971D01*
X980569Y-44721D01*
X981443Y-46763D01*
X982753Y-48221D01*
X984499Y-48804D01*
X985809Y-48512D01*
X987338Y-47346D01*
X988211Y-46180D01*
G01X998069Y-48804D02*
Y-37138D01*
G01Y-40054D02*
X998943Y-38596D01*
X1000253Y-37429D01*
X1001999Y-37138D01*
X1003527Y-37429D01*
X1004838Y-38596D01*
X1005493Y-40637D01*
Y-48804D01*
G01X1016006Y-40929D02*
X1022993D01*
X1022338Y-38887D01*
X1021246Y-37721D01*
X1019718Y-37138D01*
X1018189Y-37429D01*
X1016879Y-38304D01*
X1016006Y-40346D01*
X1015569Y-42096D01*
Y-43846D01*
X1016006Y-45596D01*
X1017098Y-47346D01*
X1018408Y-48512D01*
X1019936Y-48804D01*
X1021464Y-48221D01*
X1022993Y-46471D01*
G01X1033724Y-48804D02*
Y-37138D01*
G01Y-39471D02*
X1034816Y-38304D01*
X1035908Y-37429D01*
X1037436Y-37138D01*
X1038527Y-37429D01*
X1039838Y-38304D01*
G01X1080481Y-76304D02*
X1078734Y-76887D01*
X1077424Y-78346D01*
X1076551Y-80095D01*
X1075896Y-82429D01*
X1075678Y-85054D01*
X1075896Y-87679D01*
X1076551Y-90013D01*
X1077424Y-91763D01*
X1078734Y-93221D01*
X1080481Y-93804D01*
X1082227Y-93221D01*
X1083538Y-91763D01*
X1084411Y-90013D01*
X1085066Y-87679D01*
X1085284Y-85054D01*
X1085066Y-82429D01*
X1084411Y-80095D01*
X1083538Y-78346D01*
X1082227Y-76887D01*
X1080481Y-76304D01*
G01X1097981Y-93804D02*
X1099509Y-93512D01*
X1101256Y-92638D01*
X1102348Y-91180D01*
X1102784Y-89137D01*
X1102348Y-87096D01*
X1101038Y-85346D01*
X1099073Y-84471D01*
X1096889D01*
X1095579Y-83887D01*
X1094487Y-82429D01*
X1094051Y-80388D01*
X1094706Y-78346D01*
X1096234Y-76887D01*
X1097981Y-76304D01*
X1099727Y-76887D01*
X1101256Y-78346D01*
X1101911Y-80388D01*
X1101474Y-82429D01*
X1100383Y-83887D01*
X1099073Y-84471D01*
X1096889D01*
X1094924Y-85346D01*
X1093614Y-87096D01*
X1093178Y-89137D01*
X1093614Y-91180D01*
X1094706Y-92638D01*
X1096453Y-93512D01*
X1097981Y-93804D01*
G01X1111551Y-94387D02*
X1119411Y-76304D01*
G01X1132981D02*
X1131234Y-76887D01*
X1129924Y-78346D01*
X1129051Y-80095D01*
X1128396Y-82429D01*
X1128178Y-85054D01*
X1128396Y-87679D01*
X1129051Y-90013D01*
X1129924Y-91763D01*
X1131234Y-93221D01*
X1132981Y-93804D01*
X1134727Y-93221D01*
X1136038Y-91763D01*
X1136911Y-90013D01*
X1137566Y-87679D01*
X1137784Y-85054D01*
X1137566Y-82429D01*
X1136911Y-80095D01*
X1136038Y-78346D01*
X1134727Y-76887D01*
X1132981Y-76304D01*
G01X1150044Y-93804D02*
X1150481Y-90013D01*
X1151136Y-86804D01*
X1152009Y-83887D01*
X1153101Y-80679D01*
X1154848Y-76304D01*
X1146114D01*
G01X1164051Y-94387D02*
X1171911Y-76304D01*
G01X1181333Y-79221D02*
X1182643Y-77471D01*
X1184171Y-76596D01*
X1185918Y-76304D01*
X1188101Y-76887D01*
X1189629Y-78346D01*
X1190066Y-80095D01*
X1189848Y-81846D01*
X1188974Y-83304D01*
X1184608Y-86221D01*
X1182643Y-88262D01*
X1181333Y-91180D01*
X1180896Y-93804D01*
X1190066D01*
G01X1202981Y-76304D02*
X1201234Y-76887D01*
X1199924Y-78346D01*
X1199051Y-80095D01*
X1198396Y-82429D01*
X1198178Y-85054D01*
X1198396Y-87679D01*
X1199051Y-90013D01*
X1199924Y-91763D01*
X1201234Y-93221D01*
X1202981Y-93804D01*
X1204727Y-93221D01*
X1206038Y-91763D01*
X1206911Y-90013D01*
X1207566Y-87679D01*
X1207784Y-85054D01*
X1207566Y-82429D01*
X1206911Y-80095D01*
X1206038Y-78346D01*
X1204727Y-76887D01*
X1202981Y-76304D01*
G01X1220481Y-93804D02*
Y-76304D01*
X1217861Y-79804D01*
G01Y-93804D02*
X1223101D01*
G01X1237544D02*
X1237981Y-90013D01*
X1238636Y-86804D01*
X1239509Y-83887D01*
X1240601Y-80679D01*
X1242348Y-76304D01*
X1233614D01*
G01X1128178Y-48804D02*
Y-31304D01*
X1132544D01*
X1134291Y-32179D01*
X1135601Y-33346D01*
X1136693Y-35095D01*
X1137566Y-37138D01*
X1137784Y-40054D01*
X1137566Y-42971D01*
X1136693Y-45013D01*
X1135601Y-46763D01*
X1134291Y-47929D01*
X1132544Y-48804D01*
X1128178D01*
G01X1154411D02*
Y-37138D01*
G01Y-39179D02*
X1153538Y-38013D01*
X1152227Y-37429D01*
X1150699Y-37138D01*
X1149171Y-37721D01*
X1147861Y-38887D01*
X1146987Y-40637D01*
X1146551Y-42971D01*
X1146987Y-45304D01*
X1147861Y-47054D01*
X1149171Y-48221D01*
X1150699Y-48804D01*
X1152227Y-48512D01*
X1153538Y-47638D01*
X1154411Y-46471D01*
G01X1167981Y-31304D02*
Y-48804D01*
G01X1164924Y-37138D02*
X1171038D01*
G01X1182206Y-40929D02*
X1189193D01*
X1188538Y-38887D01*
X1187446Y-37721D01*
X1185918Y-37138D01*
X1184389Y-37429D01*
X1183079Y-38304D01*
X1182206Y-40346D01*
X1181769Y-42096D01*
Y-43846D01*
X1182206Y-45596D01*
X1183298Y-47346D01*
X1184608Y-48512D01*
X1186136Y-48804D01*
X1187664Y-48221D01*
X1189193Y-46471D01*
G54D19*
X49306Y532622D03*
X41865Y532638D03*
X49385Y555153D03*
X41885D03*
X49306Y538249D03*
X41758Y538254D03*
X49306Y543876D03*
X41858Y543881D03*
X49306Y526995D03*
X41875D03*
X49306Y521269D03*
X41832Y521271D03*
X49385Y549526D03*
X41903Y549508D03*
X49385Y560879D03*
X41800Y560900D03*
X58500Y575850D03*
X54156Y571795D03*
X140400Y479700D03*
Y483900D03*
X116172Y497305D03*
X128200Y610500D03*
X129800Y630800D03*
Y634900D03*
Y639000D03*
X200200Y489500D03*
X174900Y530700D03*
X160289Y520812D03*
X187680Y520045D03*
X187238Y536101D03*
X178086Y513171D03*
X150503Y509389D03*
X197100Y528500D03*
X175487Y587147D03*
X188110Y617688D03*
X190104Y636190D03*
X197570Y636210D03*
X151700Y590500D03*
X207000Y642300D03*
X191245Y642681D03*
X199100Y642800D03*
X219700Y471100D03*
X228425Y484151D03*
X252400Y543600D03*
X242920Y562521D03*
X219453Y528088D03*
X225508Y637894D03*
X215200Y634500D03*
X227548Y581666D03*
X238900Y597500D03*
X268700Y588500D03*
X252900Y571100D03*
Y567100D03*
X245130Y571032D03*
X244830Y566732D03*
X296520Y561123D03*
X347600Y574900D03*
X318022Y606283D03*
X307800Y661300D03*
X377200Y31000D03*
X365700Y574900D03*
X360933Y673696D03*
X360800Y665580D03*
X461660Y25990D03*
X493660Y37883D03*
X441400Y37800D03*
X521290Y77700D03*
X699744Y480189D03*
X754979Y538718D03*
X770194Y540231D03*
X762705Y538797D03*
X831439Y340820D03*
X816896Y428321D03*
G54D55*
X340631Y384824D03*
X336756Y392324D03*
X344506D03*
G54D28*
X90157Y413582D03*
X309055Y157677D03*
G54D37*
X100130Y576452D03*
X85700Y681400D03*
X171969Y579940D03*
X211700Y638400D03*
X216200Y467300D03*
X222019Y634188D03*
X297800Y527900D03*
X328123Y579949D03*
X698225Y445986D03*
X687000Y496509D03*
Y500209D03*
X883986Y269745D03*
X861498Y348715D03*
G54D46*
X141887Y560491D03*
X146567Y560391D03*
X151257Y560423D03*
X203000Y517200D03*
X198000D03*
X208000D03*
X144037Y549486D03*
X197230Y571870D03*
X181505Y575791D03*
X160964Y717468D03*
X218000Y517200D03*
X493500Y53700D03*
X446403Y31900D03*
X506500Y53700D03*
X860504Y168244D03*
X861511Y357363D03*
G54D64*
X488838Y164744D03*
G54D29*
X127400Y504600D03*
X152316Y570305D03*
X175579Y583387D03*
X207500Y634400D03*
X254800Y609800D03*
X288336Y598419D03*
X359489Y540188D03*
X369409Y509699D03*
X365780Y551390D03*
X671232Y486702D03*
Y490702D03*
Y494202D03*
Y482602D03*
G54D47*
X141887Y566091D03*
X146567Y565991D03*
X151257Y566023D03*
X203000Y522800D03*
X198000D03*
X208000D03*
X144037Y555086D03*
X197230Y577470D03*
X181505Y581391D03*
X160964Y723068D03*
X218000Y522800D03*
X493500Y59300D03*
X446403Y37500D03*
X506500Y59300D03*
X860504Y173844D03*
X861511Y362963D03*
G54D38*
X103730Y576452D03*
X89300Y681400D03*
X175569Y579940D03*
X219800Y467300D03*
X225619Y634188D03*
X215300Y638400D03*
X301400Y527900D03*
X331723Y579949D03*
X701825Y445986D03*
X690600Y496509D03*
Y500209D03*
X887586Y269745D03*
X865098Y348715D03*
G54D65*
X526025Y64390D03*
X518275D03*
X522150Y71890D03*
X824116Y334544D03*
X827991Y327044D03*
X820241D03*
G54D56*
X305906Y388386D03*
G54D48*
X163189Y669291D03*
G54D66*
X706299Y83661D03*
Y201771D03*
X804724Y83661D03*
Y201772D03*
G54D39*
X96287Y576499D03*
X143823Y615646D03*
X250300Y633600D03*
X354662Y523046D03*
X308700Y515500D03*
X360980Y590486D03*
X586447Y60807D03*
X815334Y393662D03*
X806825Y424215D03*
G54D57*
X354800Y612600D03*
X351200D03*
G54D49*
X214040Y504230D03*
X216600D03*
X219160D03*
Y497730D03*
X214040D03*
G54D58*
X380500Y24500D03*
X369500D03*
X478429Y25800D03*
X467429D03*
G54D67*
X695210Y460886D03*
X697770D03*
X700330D03*
X702890D03*
Y473686D03*
X700330D03*
X697770D03*
X695210D03*
X811748Y409837D03*
X814308D03*
X816868D03*
X819428D03*
Y422637D03*
X816868D03*
X814308D03*
X811748D03*
G54D68*
X666929Y510236D03*
X765354D03*
G54D59*
X421653Y126378D03*
X428740Y121654D03*
X421653Y130709D03*
X428740Y125985D03*
X421653Y136221D03*
X428740Y131496D03*
Y135827D03*
X421653Y183071D03*
Y140551D03*
Y144882D03*
X428740Y140158D03*
X421653Y150394D03*
X428740Y145670D03*
X421653Y154725D03*
X428740Y150000D03*
X421653Y159055D03*
X428740Y154331D03*
X421653Y164567D03*
X428740Y159843D03*
X421653Y168898D03*
X428740Y164173D03*
X421653Y173229D03*
X428740Y168504D03*
X421653Y178740D03*
X428740Y174016D03*
X435827Y126378D03*
X450000D03*
X464173D03*
X442913Y121654D03*
X457086D03*
X471260D03*
X435827Y130709D03*
X442913Y125985D03*
X450000Y130709D03*
X457086Y125985D03*
X464173Y130709D03*
X471260Y125985D03*
X435827Y136221D03*
X442913Y131496D03*
X450000Y136221D03*
X457086Y131496D03*
X464173Y136221D03*
X471260Y131496D03*
X442913Y135827D03*
X457086D03*
X471260D03*
X435827Y183071D03*
X450000D03*
X464173D03*
X435827Y140551D03*
X450000D03*
X464173D03*
X435827Y144882D03*
X442913Y140158D03*
X450000Y144882D03*
X457086Y140158D03*
X464173Y144882D03*
X471260Y140158D03*
X435827Y150394D03*
X442913Y145670D03*
X450000Y150394D03*
X457086Y145670D03*
X464173Y150394D03*
X471260Y145670D03*
X435827Y154725D03*
X442913Y150000D03*
X450000Y154725D03*
X457086Y150000D03*
X464173Y154725D03*
X471260Y150000D03*
X435827Y159055D03*
X442913Y154331D03*
X450000Y159055D03*
X457086Y154331D03*
X464173Y159055D03*
X471260Y154331D03*
X435827Y164567D03*
X442913Y159843D03*
X450000Y164567D03*
X457086Y159843D03*
X464173Y164567D03*
X471260Y159843D03*
X435827Y168898D03*
X442913Y164173D03*
X450000Y168898D03*
X457086Y164173D03*
X464173Y168898D03*
X471260Y164173D03*
X435827Y173229D03*
X442913Y168504D03*
X450000Y173229D03*
X457086Y168504D03*
X464173Y173229D03*
X471260Y168504D03*
X435827Y178740D03*
X442913Y174016D03*
X450000Y178740D03*
X457086Y174016D03*
X464173Y178740D03*
X471260Y174016D03*
X506693Y126378D03*
X520866D03*
X535039D03*
X549212D03*
X513779Y121654D03*
X527953D03*
X542126D03*
X556299D03*
X506693Y130709D03*
X513779Y125985D03*
X520866Y130709D03*
X527953Y125985D03*
X535039Y130709D03*
X542126Y125985D03*
X549212Y130709D03*
X556299Y125985D03*
X506693Y136221D03*
X513779Y131496D03*
X520866Y136221D03*
X527953Y131496D03*
X535039Y136221D03*
X542126Y131496D03*
X549212Y136221D03*
X556299Y131496D03*
X513779Y135827D03*
X527953D03*
X542126D03*
X556299D03*
X506693Y183071D03*
X520866D03*
X535039D03*
X549212D03*
X506693Y140551D03*
X520866D03*
X535039D03*
X549212D03*
X506693Y144882D03*
X513779Y140158D03*
X520866Y144882D03*
X527953Y140158D03*
X535039Y144882D03*
X542126Y140158D03*
X549212Y144882D03*
X556299Y140158D03*
X506693Y150394D03*
X513779Y145670D03*
X520866Y150394D03*
X527953Y145670D03*
X535039Y150394D03*
X542126Y145670D03*
X549212Y150394D03*
X556299Y145670D03*
X506693Y154725D03*
X513779Y150000D03*
X520866Y154725D03*
X527953Y150000D03*
X535039Y154725D03*
X542126Y150000D03*
X549212Y154725D03*
X556299Y150000D03*
X506693Y159055D03*
X513779Y154331D03*
X520866Y159055D03*
X527953Y154331D03*
X535039Y159055D03*
X542126Y154331D03*
X549212Y159055D03*
X556299Y154331D03*
X506693Y164567D03*
X513779Y159843D03*
X520866Y164567D03*
X527953Y159843D03*
X535039Y164567D03*
X542126Y159843D03*
X549212Y164567D03*
X556299Y159843D03*
X506693Y168898D03*
X513779Y164173D03*
X520866Y168898D03*
X527953Y164173D03*
X535039Y168898D03*
X542126Y164173D03*
X549212Y168898D03*
X556299Y164173D03*
X506693Y173229D03*
X513779Y168504D03*
X520866Y173229D03*
X527953Y168504D03*
X535039Y173229D03*
X542126Y168504D03*
X549212Y173229D03*
X556299Y168504D03*
X506693Y178740D03*
X513779Y174016D03*
X520866Y178740D03*
X527953Y174016D03*
X535039Y178740D03*
X542126Y174016D03*
X549212Y178740D03*
X556299Y174016D03*
G54D69*
X745669Y510236D03*
X844094D03*
M02*
